FILE_TYPE = MACRO_DRAWING;
SET COLOR_WIRE YELLOW;
SET COLOR_PROP ORANGE;
SET COLOR_DOT WHITE;
SET COLOR_ARC YELLOW;
SET COLOR_BODY GREEN;
SET COLOR_NOTE PURPLE;
SET PROP_DISPLAY VALUE;
SET PAGE_NUMBER P173;
FORCEADD OFFPAGE..1
(-7125 4300);
FORCEPROP 2 LAST $XR0 169 
J 0
(-7407 4300);
DISPLAY 0.638298 (-7407 4300);
PAINT MONO (-7407 4300);
FORCEPROP 2 LAST PATH I1
J 0
(-7075 4375);
DISPLAY 1.021277 (-7075 4375);
DISPLAY INVISIBLE (-7075 4375);
FORCEPROP 1 LAST COMMENT_BODY TRUE
J 0
(-7000 4200);
DISPLAY 0.872340 (-7000 4200);
PAINT GREEN (-7000 4200);
DISPLAY INVISIBLE (-7000 4200);
FORCEPROP 1 LAST OFFPAGE TRUE
J 0
(-6800 4175);
DISPLAY 0.872340 (-6800 4175);
PAINT GREEN (-6800 4175);
DISPLAY INVISIBLE (-6800 4175);
FORCEPROP 2 LAST CDS_LIB standard
J 2
(-7125 4300);
DISPLAY INVISIBLE (-7125 4300);
FORCEADD OFFPAGE..2
R 2
(-7175 4900);
FORCEPROP 2 LAST $XR0 169 
J 0
(-7460 4900);
DISPLAY 0.638298 (-7460 4900);
PAINT MONO (-7460 4900);
FORCEPROP 2 LAST PATH I10
J 0
(-7125 4975);
DISPLAY 1.021277 (-7125 4975);
DISPLAY INVISIBLE (-7125 4975);
FORCEPROP 1 LAST COMMENT_BODY TRUE
J 2
(-7130 4805);
DISPLAY 0.872340 (-7130 4805);
PAINT GREEN (-7130 4805);
DISPLAY INVISIBLE (-7130 4805);
FORCEPROP 1 LAST OFFPAGE TRUE
J 2
(-7500 4775);
DISPLAY 0.872340 (-7500 4775);
PAINT GREEN (-7500 4775);
DISPLAY INVISIBLE (-7500 4775);
FORCEPROP 2 LAST CDS_LIB standard
J 2
(-7175 4900);
DISPLAY INVISIBLE (-7175 4900);
FORCEADD VCC_CORE..1
(-3875 6025);
FORCEPROP 3 LASTPIN (-3875 5975) SIG_NAME SW_P12V_STBY_PVDDCR_SOC_P0_FLT\g
J 0
(-3865 5985);
DISPLAY 0.659574 (-3865 5985);
PAINT MONO (-3865 5985);
DISPLAY INVISIBLE (-3865 5985);
FORCEPROP 1 LAST HDL_POWER SW_P12V_STBY_PVDDCR_SOC_P0_FLT
J 1
(-3875 6075);
DISPLAY 0.489362 (-3875 6075);
PAINT GREEN (-3875 6075);
FORCEPROP 2 LAST CDS_LIB pure_quanta_power
J 0
(-3875 6025);
DISPLAY INVISIBLE (-3875 6025);
FORCEPROP 1 LAST PATH I102
J 0
(-3825 6050);
DISPLAY 0.872340 (-3825 6050);
PAINT AQUA (-3825 6050);
DISPLAY INVISIBLE (-3825 6050);
FORCEADD VCC_CORE..1
(-1150 3350);
FORCEPROP 3 LASTPIN (-1150 3300) SIG_NAME PVDDCR_SOC_P0\g
J 0
(-1140 3310);
DISPLAY 0.659574 (-1140 3310);
PAINT MONO (-1140 3310);
DISPLAY INVISIBLE (-1140 3310);
FORCEPROP 1 LAST HDL_POWER PVDDCR_SOC_P0
J 1
(-1150 3400);
DISPLAY 0.489362 (-1150 3400);
PAINT GREEN (-1150 3400);
FORCEPROP 2 LAST CDS_LIB pure_quanta_power
J 0
(-1150 3350);
DISPLAY INVISIBLE (-1150 3350);
FORCEPROP 1 LAST PATH I104
J 0
(-1100 3375);
DISPLAY 0.872340 (-1100 3375);
PAINT AQUA (-1100 3375);
DISPLAY INVISIBLE (-1100 3375);
FORCEADD UNIVERSAL_GND..1
(-1150 2725);
FORCEPROP 3 LASTPIN (-1150 2775) SIG_NAME GND\g
J 0
(-1140 2785);
DISPLAY 0.659574 (-1140 2785);
PAINT MONO (-1140 2785);
DISPLAY INVISIBLE (-1140 2785);
FORCEPROP 2 LAST CDS_LIB pure_quanta_power
J 0
(-1150 2725);
DISPLAY INVISIBLE (-1150 2725);
FORCEPROP 1 LAST PATH I105
J 0
(-1075 2725);
DISPLAY 0.872340 (-1075 2725);
PAINT AQUA (-1075 2725);
DISPLAY INVISIBLE (-1075 2725);
FORCEPROP 1 LAST HDL_POWER GND
J 1
(-1125 2650);
DISPLAY 0.872340 (-1125 2650);
PAINT GREEN (-1125 2650);
DISPLAY INVISIBLE (-1125 2650);
FORCEADD Q_CAPP..1
(-3425 5750);
FORCEPROP 1 LAST LOCATION PC596
J 0
(-3375 5850);
DISPLAY 0.489362 (-3375 5850);
PAINT SKYBLUE (-3375 5850);
FORCEPROP 0 LAST $SEC 1
J 0
(-3375 5900);
DISPLAY 0.680851 (-3375 5900);
PAINT MONO (-3375 5900);
DISPLAY INVISIBLE (-3375 5900);
FORCEPROP 0 LAST CDS_SEC 1
J 0
(-3375 5900);
DISPLAY 1.021277 (-3375 5900);
DISPLAY INVISIBLE (-3375 5900);
FORCEPROP 1 LASTPIN (-3425 5850) $PN 1
J 0
(-3415 5835);
DISPLAY 0.489362 (-3415 5835);
PAINT MONO (-3415 5835);
FORCEPROP 1 LASTPIN (-3425 5650) $PN 2
J 0
(-3415 5635);
DISPLAY 0.489362 (-3415 5635);
PAINT MONO (-3415 5635);
FORCEPROP 1 LAST PART_NUMBER CC72204MD02
J 0
(-3375 5550);
DISPLAY 0.489362 (-3375 5550);
PAINT SKYBLUE (-3375 5550);
FORCEPROP 1 LAST MATERIAL OSCON
J 0
(-3375 5650);
DISPLAY 0.489362 (-3375 5650);
PAINT SKYBLUE (-3375 5650);
FORCEPROP 1 LAST TOLERANCE 20%
J 0
(-3375 5750);
DISPLAY 0.489362 (-3375 5750);
PAINT SKYBLUE (-3375 5750);
FORCEPROP 1 LAST VALUE 220UF
J 0
(-3375 5800);
DISPLAY 0.489362 (-3375 5800);
PAINT SKYBLUE (-3375 5800);
FORCEPROP 1 LAST VOLTAGE 25V
J 0
(-3375 5700);
DISPLAY 0.489362 (-3375 5700);
PAINT SKYBLUE (-3375 5700);
FORCEPROP 1 LAST PACK_TYPE THLF
J 0
(-3375 5600);
DISPLAY 0.489362 (-3375 5600);
PAINT SKYBLUE (-3375 5600);
FORCEPROP 2 LAST CDS_LIB pure_quanta
J 0
(-3425 5750);
DISPLAY INVISIBLE (-3425 5750);
FORCEPROP 1 LAST PATH I106
J 0
(-3375 5900);
DISPLAY 0.978723 (-3375 5900);
DISPLAY INVISIBLE (-3375 5900);
FORCEADD Q_CAPP..1
(-1150 3075);
FORCEPROP 1 LAST LOCATION PC601
J 0
(-1100 3175);
DISPLAY 0.489362 (-1100 3175);
PAINT SKYBLUE (-1100 3175);
FORCEPROP 0 LAST $SEC 1
J 0
(-1100 3225);
DISPLAY 0.680851 (-1100 3225);
PAINT MONO (-1100 3225);
DISPLAY INVISIBLE (-1100 3225);
FORCEPROP 0 LAST CDS_SEC 1
J 0
(-1100 3225);
DISPLAY 1.021277 (-1100 3225);
DISPLAY INVISIBLE (-1100 3225);
FORCEPROP 1 LASTPIN (-1150 3175) $PN 1
J 0
(-1140 3160);
DISPLAY 0.489362 (-1140 3160);
PAINT MONO (-1140 3160);
FORCEPROP 1 LASTPIN (-1150 2975) $PN 2
J 0
(-1140 2960);
DISPLAY 0.489362 (-1140 2960);
PAINT MONO (-1140 2960);
FORCEPROP 1 LAST MATERIAL SPCAP
J 0
(-1100 2975);
DISPLAY 0.489362 (-1100 2975);
PAINT SKYBLUE (-1100 2975);
FORCEPROP 1 LAST TOLERANCE 20%
J 0
(-1100 3075);
DISPLAY 0.489362 (-1100 3075);
PAINT SKYBLUE (-1100 3075);
FORCEPROP 1 LAST VALUE 470UF
J 0
(-1100 3125);
DISPLAY 0.489362 (-1100 3125);
PAINT SKYBLUE (-1100 3125);
FORCEPROP 1 LAST PART_NUMBER CH747LM8825
J 0
(-1100 2875);
DISPLAY 0.489362 (-1100 2875);
PAINT SKYBLUE (-1100 2875);
FORCEPROP 1 LAST VOLTAGE 2.5V
J 0
(-1100 3025);
DISPLAY 0.489362 (-1100 3025);
PAINT SKYBLUE (-1100 3025);
FORCEPROP 1 LAST PACK_TYPE SMLF
J 0
(-1100 2925);
DISPLAY 0.489362 (-1100 2925);
PAINT SKYBLUE (-1100 2925);
FORCEPROP 2 LAST CDS_LIB pure_quanta
J 0
(-1150 3075);
DISPLAY INVISIBLE (-1150 3075);
FORCEPROP 1 LAST PATH I107
J 0
(-1100 3225);
DISPLAY 0.978723 (-1100 3225);
DISPLAY INVISIBLE (-1100 3225);
FORCEADD Q_CAP..1
(-5425 5750);
FORCEPROP 1 LAST LOCATION PC583_1
J 0
(-5375 5850);
DISPLAY 0.489362 (-5375 5850);
PAINT SKYBLUE (-5375 5850);
FORCEPROP 0 LAST $SEC 1
J 0
(-5375 5900);
DISPLAY 0.680851 (-5375 5900);
PAINT MONO (-5375 5900);
DISPLAY INVISIBLE (-5375 5900);
FORCEPROP 0 LAST CDS_SEC 1
J 0
(-5375 5900);
DISPLAY 1.021277 (-5375 5900);
DISPLAY INVISIBLE (-5375 5900);
FORCEPROP 1 LASTPIN (-5425 5850) $PN 1
J 0
(-5415 5830);
DISPLAY 0.489362 (-5415 5830);
PAINT MONO (-5415 5830);
FORCEPROP 1 LASTPIN (-5425 5650) $PN 2
J 0
(-5415 5630);
DISPLAY 0.489362 (-5415 5630);
PAINT MONO (-5415 5630);
FORCEPROP 1 LAST MATERIAL X7R
J 0
(-5375 5650);
DISPLAY 0.489362 (-5375 5650);
PAINT SKYBLUE (-5375 5650);
FORCEPROP 1 LAST TOLERANCE 10%
J 0
(-5375 5700);
DISPLAY 0.489362 (-5375 5700);
PAINT SKYBLUE (-5375 5700);
FORCEPROP 1 LAST VALUE 0.1UF
J 0
(-5375 5800);
DISPLAY 0.489362 (-5375 5800);
PAINT SKYBLUE (-5375 5800);
FORCEPROP 1 LAST VOLTAGE 25V
J 0
(-5375 5750);
DISPLAY 0.489362 (-5375 5750);
PAINT SKYBLUE (-5375 5750);
FORCEPROP 1 LAST PART_NUMBER CH4104K1B00
J 0
(-5375 5600);
DISPLAY 0.489362 (-5375 5600);
PAINT SKYBLUE (-5375 5600);
FORCEPROP 1 LAST PACK_TYPE 0402
J 0
(-5375 5550);
DISPLAY 0.489362 (-5375 5550);
PAINT SKYBLUE (-5375 5550);
FORCEPROP 2 LAST CDS_LIB pure_quanta
J 0
(-5425 5750);
DISPLAY INVISIBLE (-5425 5750);
FORCEPROP 1 LAST PATH I108
J 0
(-5375 5900);
DISPLAY 0.978723 (-5375 5900);
PAINT WHITE (-5375 5900);
DISPLAY INVISIBLE (-5375 5900);
FORCEADD Q_CAP..1
(-5350 2700);
FORCEPROP 1 LAST LOCATION PC584_2
J 0
(-5300 2800);
DISPLAY 0.489362 (-5300 2800);
PAINT SKYBLUE (-5300 2800);
FORCEPROP 0 LAST $SEC 1
J 0
(-5300 2850);
DISPLAY 0.680851 (-5300 2850);
PAINT MONO (-5300 2850);
DISPLAY INVISIBLE (-5300 2850);
FORCEPROP 0 LAST CDS_SEC 1
J 0
(-5300 2850);
DISPLAY 1.021277 (-5300 2850);
DISPLAY INVISIBLE (-5300 2850);
FORCEPROP 1 LASTPIN (-5350 2800) $PN 1
J 0
(-5340 2780);
DISPLAY 0.489362 (-5340 2780);
PAINT MONO (-5340 2780);
FORCEPROP 1 LASTPIN (-5350 2600) $PN 2
J 0
(-5340 2580);
DISPLAY 0.489362 (-5340 2580);
PAINT MONO (-5340 2580);
FORCEPROP 1 LAST MATERIAL X7R
J 0
(-5300 2600);
DISPLAY 0.489362 (-5300 2600);
PAINT SKYBLUE (-5300 2600);
FORCEPROP 1 LAST TOLERANCE 10%
J 0
(-5300 2650);
DISPLAY 0.489362 (-5300 2650);
PAINT SKYBLUE (-5300 2650);
FORCEPROP 1 LAST VALUE 0.1UF
J 0
(-5300 2750);
DISPLAY 0.489362 (-5300 2750);
PAINT SKYBLUE (-5300 2750);
FORCEPROP 1 LAST VOLTAGE 25V
J 0
(-5300 2700);
DISPLAY 0.489362 (-5300 2700);
PAINT SKYBLUE (-5300 2700);
FORCEPROP 1 LAST PACK_TYPE 0402
J 0
(-5300 2500);
DISPLAY 0.489362 (-5300 2500);
PAINT SKYBLUE (-5300 2500);
FORCEPROP 1 LAST PART_NUMBER CH4104K1B00
J 0
(-5300 2550);
DISPLAY 0.489362 (-5300 2550);
PAINT SKYBLUE (-5300 2550);
FORCEPROP 2 LAST CDS_LIB pure_quanta
J 0
(-5350 2700);
DISPLAY INVISIBLE (-5350 2700);
FORCEPROP 1 LAST PATH I109
J 0
(-5300 2850);
DISPLAY 0.978723 (-5300 2850);
PAINT WHITE (-5300 2850);
DISPLAY INVISIBLE (-5300 2850);
FORCEADD Q_CAP..1
(-7525 5250);
FORCEPROP 1 LAST LOCATION PC579
J 0
(-7475 5350);
DISPLAY 0.489362 (-7475 5350);
PAINT SKYBLUE (-7475 5350);
FORCEPROP 0 LAST $SEC 1
J 0
(-7475 5400);
DISPLAY 0.680851 (-7475 5400);
PAINT MONO (-7475 5400);
DISPLAY INVISIBLE (-7475 5400);
FORCEPROP 0 LAST CDS_SEC 1
J 0
(-7475 5400);
DISPLAY 1.021277 (-7475 5400);
DISPLAY INVISIBLE (-7475 5400);
FORCEPROP 1 LASTPIN (-7525 5350) $PN 1
J 0
(-7515 5330);
DISPLAY 0.489362 (-7515 5330);
PAINT MONO (-7515 5330);
FORCEPROP 1 LASTPIN (-7525 5150) $PN 2
J 0
(-7515 5130);
DISPLAY 0.489362 (-7515 5130);
PAINT MONO (-7515 5130);
FORCEPROP 1 LAST MATERIAL X6S
J 0
(-7475 5150);
DISPLAY 0.489362 (-7475 5150);
PAINT SKYBLUE (-7475 5150);
FORCEPROP 1 LAST TOLERANCE 10%
J 0
(-7475 5200);
DISPLAY 0.489362 (-7475 5200);
PAINT SKYBLUE (-7475 5200);
FORCEPROP 1 LAST VALUE 2.2UF
J 0
(-7475 5300);
DISPLAY 0.489362 (-7475 5300);
PAINT SKYBLUE (-7475 5300);
FORCEPROP 1 LAST PART_NUMBER CH5222KEB01
J 0
(-7475 5100);
DISPLAY 0.489362 (-7475 5100);
PAINT SKYBLUE (-7475 5100);
FORCEPROP 1 LAST VOLTAGE 10V
J 0
(-7475 5250);
DISPLAY 0.489362 (-7475 5250);
PAINT SKYBLUE (-7475 5250);
FORCEPROP 1 LAST PACK_TYPE C0402
J 0
(-7475 5050);
DISPLAY 0.489362 (-7475 5050);
PAINT SKYBLUE (-7475 5050);
FORCEPROP 2 LAST CDS_LIB pure_quanta
J 0
(-7525 5250);
DISPLAY INVISIBLE (-7525 5250);
FORCEPROP 1 LAST PATH I110
J 0
(-7475 5400);
DISPLAY 0.978723 (-7475 5400);
PAINT WHITE (-7475 5400);
DISPLAY INVISIBLE (-7475 5400);
FORCEADD UNIVERSAL_GND..1
(-7525 5050);
FORCEPROP 3 LASTPIN (-7525 5100) SIG_NAME GND\g
J 0
(-7515 5110);
DISPLAY 0.659574 (-7515 5110);
PAINT MONO (-7515 5110);
DISPLAY INVISIBLE (-7515 5110);
FORCEPROP 2 LAST CDS_LIB pure_quanta_power
J 0
(-7525 5050);
DISPLAY INVISIBLE (-7525 5050);
FORCEPROP 1 LAST PATH I111
J 0
(-7450 5050);
DISPLAY 0.872340 (-7450 5050);
PAINT AQUA (-7450 5050);
DISPLAY INVISIBLE (-7450 5050);
FORCEPROP 1 LAST HDL_POWER GND
J 1
(-7500 4975);
DISPLAY 0.872340 (-7500 4975);
PAINT GREEN (-7500 4975);
DISPLAY INVISIBLE (-7500 4975);
FORCEADD UNIVERSAL_GND..1
(-7175 5500);
FORCEPROP 3 LASTPIN (-7175 5550) SIG_NAME GND\g
J 0
(-7165 5560);
DISPLAY 0.659574 (-7165 5560);
PAINT MONO (-7165 5560);
DISPLAY INVISIBLE (-7165 5560);
FORCEPROP 2 LAST CDS_LIB pure_quanta_power
J 0
(-7175 5500);
DISPLAY INVISIBLE (-7175 5500);
FORCEPROP 1 LAST PATH I112
J 0
(-7100 5500);
DISPLAY 0.872340 (-7100 5500);
PAINT AQUA (-7100 5500);
DISPLAY INVISIBLE (-7100 5500);
FORCEPROP 1 LAST HDL_POWER GND
J 1
(-7150 5425);
DISPLAY 0.872340 (-7150 5425);
PAINT GREEN (-7150 5425);
DISPLAY INVISIBLE (-7150 5425);
FORCEADD Q_RES..2
(-7525 5750);
FORCEPROP 1 LAST LOCATION PR356
J 0
(-7480 5850);
DISPLAY 0.489362 (-7480 5850);
PAINT SKYBLUE (-7480 5850);
FORCEPROP 0 LAST $SEC 1
J 0
(-7475 5925);
DISPLAY 0.680851 (-7475 5925);
PAINT MONO (-7475 5925);
DISPLAY INVISIBLE (-7475 5925);
FORCEPROP 0 LAST CDS_SEC 1
J 0
(-7475 5925);
DISPLAY 1.021277 (-7475 5925);
DISPLAY INVISIBLE (-7475 5925);
FORCEPROP 1 LASTPIN (-7525 5850) $PN 1
J 0
(-7520 5812);
DISPLAY 0.489362 (-7520 5812);
PAINT MONO (-7520 5812);
FORCEPROP 1 LASTPIN (-7525 5650) $PN 2
J 0
(-7520 5660);
DISPLAY 0.489362 (-7520 5660);
PAINT MONO (-7520 5660);
FORCEPROP 1 LAST WATTAGE 1/16W
J 0
(-7475 5700);
DISPLAY 0.489362 (-7475 5700);
PAINT SKYBLUE (-7475 5700);
FORCEPROP 1 LAST MATERIAL CHIP
J 0
(-7475 5650);
DISPLAY 0.489362 (-7475 5650);
PAINT SKYBLUE (-7475 5650);
FORCEPROP 1 LAST TOLERANCE 1%
J 0
(-7475 5750);
DISPLAY 0.489362 (-7475 5750);
PAINT SKYBLUE (-7475 5750);
FORCEPROP 1 LAST VALUE 2.2
J 0
(-7475 5800);
DISPLAY 0.489362 (-7475 5800);
PAINT SKYBLUE (-7475 5800);
FORCEPROP 1 LAST PART_NUMBER CS-2202FB00
J 0
(-7475 5600);
DISPLAY 0.489362 (-7475 5600);
PAINT SKYBLUE (-7475 5600);
FORCEPROP 1 LAST PACK_TYPE 0402LF
J 0
(-7475 5550);
DISPLAY 0.489362 (-7475 5550);
PAINT SKYBLUE (-7475 5550);
FORCEPROP 2 LAST CDS_LIB pure_quanta
J 0
(-7525 5750);
DISPLAY INVISIBLE (-7525 5750);
FORCEPROP 1 LAST PATH I113
J 0
(-7475 5925);
DISPLAY 0.978723 (-7475 5925);
PAINT WHITE (-7475 5925);
DISPLAY INVISIBLE (-7475 5925);
FORCEADD Q_CAP..1
(-7175 5750);
FORCEPROP 1 LAST LOCATION PC581_SOP0_1
J 0
(-7125 5850);
DISPLAY 0.489362 (-7125 5850);
PAINT SKYBLUE (-7125 5850);
FORCEPROP 0 LAST $SEC 1
J 0
(-7125 5900);
DISPLAY 0.680851 (-7125 5900);
PAINT MONO (-7125 5900);
DISPLAY INVISIBLE (-7125 5900);
FORCEPROP 0 LAST CDS_SEC 1
J 0
(-7125 5900);
DISPLAY 1.021277 (-7125 5900);
DISPLAY INVISIBLE (-7125 5900);
FORCEPROP 1 LASTPIN (-7175 5850) $PN 1
J 0
(-7165 5830);
DISPLAY 0.489362 (-7165 5830);
PAINT MONO (-7165 5830);
FORCEPROP 1 LASTPIN (-7175 5650) $PN 2
J 0
(-7165 5630);
DISPLAY 0.489362 (-7165 5630);
PAINT MONO (-7165 5630);
FORCEPROP 1 LAST MATERIAL X6S
J 0
(-7125 5650);
DISPLAY 0.489362 (-7125 5650);
PAINT SKYBLUE (-7125 5650);
FORCEPROP 1 LAST TOLERANCE 10%
J 0
(-7125 5700);
DISPLAY 0.489362 (-7125 5700);
PAINT SKYBLUE (-7125 5700);
FORCEPROP 1 LAST VALUE 2.2UF
J 0
(-7125 5800);
DISPLAY 0.489362 (-7125 5800);
PAINT SKYBLUE (-7125 5800);
FORCEPROP 1 LAST PART_NUMBER CH5222KEB01
J 0
(-7125 5600);
DISPLAY 0.489362 (-7125 5600);
PAINT SKYBLUE (-7125 5600);
FORCEPROP 1 LAST VOLTAGE 10V
J 0
(-7125 5750);
DISPLAY 0.489362 (-7125 5750);
PAINT SKYBLUE (-7125 5750);
FORCEPROP 1 LAST PACK_TYPE C0402
J 0
(-7125 5550);
DISPLAY 0.489362 (-7125 5550);
PAINT SKYBLUE (-7125 5550);
FORCEPROP 2 LAST CDS_LIB pure_quanta
J 0
(-7175 5750);
DISPLAY INVISIBLE (-7175 5750);
FORCEPROP 1 LAST PATH I114
J 0
(-7125 5900);
DISPLAY 0.978723 (-7125 5900);
PAINT WHITE (-7125 5900);
DISPLAY INVISIBLE (-7125 5900);
FORCEADD Q_CAP..1
(-7500 2150);
FORCEPROP 1 LAST LOCATION PC580
J 0
(-7450 2250);
DISPLAY 0.489362 (-7450 2250);
PAINT SKYBLUE (-7450 2250);
FORCEPROP 0 LAST $SEC 1
J 0
(-7450 2300);
DISPLAY 0.680851 (-7450 2300);
PAINT MONO (-7450 2300);
DISPLAY INVISIBLE (-7450 2300);
FORCEPROP 0 LAST CDS_SEC 1
J 0
(-7450 2300);
DISPLAY 1.021277 (-7450 2300);
DISPLAY INVISIBLE (-7450 2300);
FORCEPROP 1 LASTPIN (-7500 2250) $PN 1
J 0
(-7490 2230);
DISPLAY 0.489362 (-7490 2230);
PAINT MONO (-7490 2230);
FORCEPROP 1 LASTPIN (-7500 2050) $PN 2
J 0
(-7490 2030);
DISPLAY 0.489362 (-7490 2030);
PAINT MONO (-7490 2030);
FORCEPROP 1 LAST MATERIAL X6S
J 0
(-7450 2050);
DISPLAY 0.489362 (-7450 2050);
PAINT SKYBLUE (-7450 2050);
FORCEPROP 1 LAST TOLERANCE 10%
J 0
(-7450 2100);
DISPLAY 0.489362 (-7450 2100);
PAINT SKYBLUE (-7450 2100);
FORCEPROP 1 LAST VALUE 2.2UF
J 0
(-7450 2200);
DISPLAY 0.489362 (-7450 2200);
PAINT SKYBLUE (-7450 2200);
FORCEPROP 1 LAST PART_NUMBER CH5222KEB01
J 0
(-7450 2000);
DISPLAY 0.489362 (-7450 2000);
PAINT SKYBLUE (-7450 2000);
FORCEPROP 1 LAST VOLTAGE 10V
J 0
(-7450 2150);
DISPLAY 0.489362 (-7450 2150);
PAINT SKYBLUE (-7450 2150);
FORCEPROP 1 LAST PACK_TYPE C0402
J 0
(-7450 1950);
DISPLAY 0.489362 (-7450 1950);
PAINT SKYBLUE (-7450 1950);
FORCEPROP 2 LAST CDS_LIB pure_quanta
J 0
(-7500 2150);
DISPLAY INVISIBLE (-7500 2150);
FORCEPROP 1 LAST PATH I116
J 0
(-7450 2300);
DISPLAY 0.978723 (-7450 2300);
PAINT WHITE (-7450 2300);
DISPLAY INVISIBLE (-7450 2300);
FORCEADD UNIVERSAL_GND..1
(-7500 1950);
FORCEPROP 3 LASTPIN (-7500 2000) SIG_NAME GND\g
J 0
(-7490 2010);
DISPLAY 0.659574 (-7490 2010);
PAINT MONO (-7490 2010);
DISPLAY INVISIBLE (-7490 2010);
FORCEPROP 2 LAST CDS_LIB pure_quanta_power
J 0
(-7500 1950);
DISPLAY INVISIBLE (-7500 1950);
FORCEPROP 1 LAST PATH I117
J 0
(-7425 1950);
DISPLAY 0.872340 (-7425 1950);
PAINT AQUA (-7425 1950);
DISPLAY INVISIBLE (-7425 1950);
FORCEPROP 1 LAST HDL_POWER GND
J 1
(-7475 1875);
DISPLAY 0.872340 (-7475 1875);
PAINT GREEN (-7475 1875);
DISPLAY INVISIBLE (-7475 1875);
FORCEADD UNIVERSAL_GND..1
(-7150 2425);
FORCEPROP 3 LASTPIN (-7150 2475) SIG_NAME GND\g
J 0
(-7140 2485);
DISPLAY 0.659574 (-7140 2485);
PAINT MONO (-7140 2485);
DISPLAY INVISIBLE (-7140 2485);
FORCEPROP 2 LAST CDS_LIB pure_quanta_power
J 0
(-7150 2425);
DISPLAY INVISIBLE (-7150 2425);
FORCEPROP 1 LAST PATH I118
J 0
(-7075 2425);
DISPLAY 0.872340 (-7075 2425);
PAINT AQUA (-7075 2425);
DISPLAY INVISIBLE (-7075 2425);
FORCEPROP 1 LAST HDL_POWER GND
J 1
(-7125 2350);
DISPLAY 0.872340 (-7125 2350);
PAINT GREEN (-7125 2350);
DISPLAY INVISIBLE (-7125 2350);
FORCEADD Q_RES..2
(-7500 2675);
FORCEPROP 1 LAST LOCATION PR357
J 0
(-7455 2800);
DISPLAY 0.489362 (-7455 2800);
PAINT SKYBLUE (-7455 2800);
FORCEPROP 0 LAST $SEC 1
J 0
(-7450 2850);
DISPLAY 0.680851 (-7450 2850);
PAINT MONO (-7450 2850);
DISPLAY INVISIBLE (-7450 2850);
FORCEPROP 0 LAST CDS_SEC 1
J 0
(-7450 2850);
DISPLAY 1.021277 (-7450 2850);
DISPLAY INVISIBLE (-7450 2850);
FORCEPROP 1 LASTPIN (-7500 2775) $PN 1
J 0
(-7495 2737);
DISPLAY 0.489362 (-7495 2737);
PAINT MONO (-7495 2737);
FORCEPROP 1 LASTPIN (-7500 2575) $PN 2
J 0
(-7495 2585);
DISPLAY 0.489362 (-7495 2585);
PAINT MONO (-7495 2585);
FORCEPROP 1 LAST WATTAGE 1/16W
J 0
(-7450 2650);
DISPLAY 0.489362 (-7450 2650);
PAINT SKYBLUE (-7450 2650);
FORCEPROP 1 LAST MATERIAL CHIP
J 0
(-7450 2600);
DISPLAY 0.489362 (-7450 2600);
PAINT SKYBLUE (-7450 2600);
FORCEPROP 1 LAST TOLERANCE 1%
J 0
(-7450 2700);
DISPLAY 0.489362 (-7450 2700);
PAINT SKYBLUE (-7450 2700);
FORCEPROP 1 LAST VALUE 2.2
J 0
(-7450 2750);
DISPLAY 0.489362 (-7450 2750);
PAINT SKYBLUE (-7450 2750);
FORCEPROP 1 LAST PART_NUMBER CS-2202FB00
J 0
(-7450 2550);
DISPLAY 0.489362 (-7450 2550);
PAINT SKYBLUE (-7450 2550);
FORCEPROP 1 LAST PACK_TYPE 0402LF
J 0
(-7450 2500);
DISPLAY 0.489362 (-7450 2500);
PAINT SKYBLUE (-7450 2500);
FORCEPROP 2 LAST CDS_LIB pure_quanta
J 0
(-7500 2675);
DISPLAY INVISIBLE (-7500 2675);
FORCEPROP 1 LAST PATH I119
J 0
(-7450 2850);
DISPLAY 0.978723 (-7450 2850);
PAINT WHITE (-7450 2850);
DISPLAY INVISIBLE (-7450 2850);
FORCEADD Q_CAP..1
(-7150 2675);
FORCEPROP 1 LAST LOCATION PC582_SOP0_2
J 0
(-7100 2775);
DISPLAY 0.489362 (-7100 2775);
PAINT SKYBLUE (-7100 2775);
FORCEPROP 0 LAST $SEC 1
J 0
(-7100 2825);
DISPLAY 0.680851 (-7100 2825);
PAINT MONO (-7100 2825);
DISPLAY INVISIBLE (-7100 2825);
FORCEPROP 0 LAST CDS_SEC 1
J 0
(-7100 2825);
DISPLAY 1.021277 (-7100 2825);
DISPLAY INVISIBLE (-7100 2825);
FORCEPROP 1 LASTPIN (-7150 2775) $PN 1
J 0
(-7140 2755);
DISPLAY 0.489362 (-7140 2755);
PAINT MONO (-7140 2755);
FORCEPROP 1 LASTPIN (-7150 2575) $PN 2
J 0
(-7140 2555);
DISPLAY 0.489362 (-7140 2555);
PAINT MONO (-7140 2555);
FORCEPROP 1 LAST VALUE 2.2UF
J 0
(-7100 2725);
DISPLAY 0.489362 (-7100 2725);
PAINT SKYBLUE (-7100 2725);
FORCEPROP 1 LAST MATERIAL X6S
J 0
(-7100 2575);
DISPLAY 0.489362 (-7100 2575);
PAINT SKYBLUE (-7100 2575);
FORCEPROP 1 LAST TOLERANCE 10%
J 0
(-7100 2625);
DISPLAY 0.489362 (-7100 2625);
PAINT SKYBLUE (-7100 2625);
FORCEPROP 1 LAST PART_NUMBER CH5222KEB01
J 0
(-7100 2525);
DISPLAY 0.489362 (-7100 2525);
PAINT SKYBLUE (-7100 2525);
FORCEPROP 1 LAST VOLTAGE 10V
J 0
(-7100 2675);
DISPLAY 0.489362 (-7100 2675);
PAINT SKYBLUE (-7100 2675);
FORCEPROP 1 LAST PACK_TYPE C0402
J 0
(-7100 2475);
DISPLAY 0.489362 (-7100 2475);
PAINT SKYBLUE (-7100 2475);
FORCEPROP 2 LAST CDS_LIB pure_quanta
J 0
(-7150 2675);
DISPLAY INVISIBLE (-7150 2675);
FORCEPROP 1 LAST PATH I120
J 0
(-7100 2825);
DISPLAY 0.978723 (-7100 2825);
PAINT WHITE (-7100 2825);
DISPLAY INVISIBLE (-7100 2825);
FORCEADD ISL99390FRZTR5935..1
(-6025 4900);
FORCEPROP 1 LAST LOCATION PU49
J 0
(-6325 5775);
DISPLAY 0.489362 (-6325 5775);
PAINT SKYBLUE (-6325 5775);
FORCEPROP 0 LAST $SEC 1
J 0
(-6325 5925);
DISPLAY 0.680851 (-6325 5925);
PAINT MONO (-6325 5925);
DISPLAY INVISIBLE (-6325 5925);
FORCEPROP 0 LAST CDS_SEC 1
J 0
(-6325 5925);
DISPLAY 1.021277 (-6325 5925);
DISPLAY INVISIBLE (-6325 5925);
FORCEPROP 0 LASTPIN (-5625 4450) $PN 2
J 0
(-5615 4460);
DISPLAY 0.489362 (-5615 4460);
PAINT MONO (-5615 4460);
FORCEPROP 0 LASTPIN (-5625 5250) $PN 33
J 0
(-5615 5260);
DISPLAY 0.489362 (-5615 5260);
PAINT MONO (-5615 5260);
FORCEPROP 0 LASTPIN (-6475 4650) $PN 31
J 2
(-6485 4660);
DISPLAY 0.489362 (-6485 4660);
PAINT MONO (-6485 4660);
FORCEPROP 0 LASTPIN (-6475 5050) $PN 35
J 2
(-6485 5060);
DISPLAY 0.489362 (-6485 5060);
PAINT MONO (-6485 5060);
FORCEPROP 0 LASTPIN (-5625 4600) $PN 6
J 0
(-5615 4610);
DISPLAY 0.489362 (-5615 4610);
PAINT MONO (-5615 4610);
FORCEPROP 0 LASTPIN (-5625 4550) $PN 41
J 0
(-5615 4560);
DISPLAY 0.489362 (-5615 4560);
PAINT MONO (-5615 4560);
FORCEPROP 0 LASTPIN (-6475 4900) $PN 38
J 2
(-6485 4910);
DISPLAY 0.489362 (-6485 4910);
PAINT MONO (-6485 4910);
FORCEPROP 0 LASTPIN (-6475 4600) $PN 37
J 2
(-6485 4610);
DISPLAY 0.489362 (-6485 4610);
PAINT MONO (-6485 4610);
FORCEPROP 0 LASTPIN (-5625 4400) $PN 5
J 0
(-5615 4410);
DISPLAY 0.489362 (-5615 4410);
PAINT MONO (-5615 4410);
FORCEPROP 0 LASTPIN (-5625 4350) $PN 7_9-20_24
J 0
(-5615 4360);
DISPLAY 0.489362 (-5615 4360);
PAINT MONO (-5615 4360);
FORCEPROP 0 LASTPIN (-5625 4300) $PN 40
J 0
(-5615 4310);
DISPLAY 0.489362 (-5615 4310);
PAINT MONO (-5615 4310);
FORCEPROP 0 LASTPIN (-5625 5000) $PN 32
J 0
(-5615 5010);
DISPLAY 0.489362 (-5615 5010);
PAINT MONO (-5615 5010);
FORCEPROP 0 LASTPIN (-6475 5550) $PN 4
J 2
(-6485 5560);
DISPLAY 0.489362 (-6485 5560);
PAINT MONO (-6485 5560);
FORCEPROP 0 LASTPIN (-6475 4300) $PN 34
J 2
(-6485 4310);
DISPLAY 0.489362 (-6485 4310);
PAINT MONO (-6485 4310);
FORCEPROP 0 LASTPIN (-6475 4800) $PN 39
J 2
(-6485 4810);
DISPLAY 0.489362 (-6485 4810);
PAINT MONO (-6485 4810);
FORCEPROP 0 LASTPIN (-5625 4900) $PN 10_19
J 0
(-5615 4910);
DISPLAY 0.489362 (-5615 4910);
PAINT MONO (-5615 4910);
FORCEPROP 0 LASTPIN (-6475 4400) $PN 36
J 2
(-6485 4410);
DISPLAY 0.489362 (-6485 4410);
PAINT MONO (-6485 4410);
FORCEPROP 0 LASTPIN (-6475 5250) $PN 3
J 2
(-6485 5260);
DISPLAY 0.489362 (-6485 5260);
PAINT MONO (-6485 5260);
FORCEPROP 0 LASTPIN (-5625 5550) $PN 25_29
J 0
(-5615 5560);
DISPLAY 0.489362 (-5615 5560);
PAINT MONO (-5615 5560);
FORCEPROP 0 LASTPIN (-5625 5500) $PN 30
J 0
(-5615 5510);
DISPLAY 0.489362 (-5615 5510);
PAINT MONO (-5615 5510);
FORCEPROP 0 LASTPIN (-5625 4650) $PN 1
J 0
(-5615 4660);
DISPLAY 0.489362 (-5615 4660);
PAINT MONO (-5615 4660);
FORCEPROP 2 LAST PART_TYPE SMLF
J 0
(-6325 5875);
DISPLAY 1.021277 (-6325 5875);
FORCEPROP 1 LAST MATERIAL IC
J 0
(-6325 5625);
DISPLAY 0.489362 (-6325 5625);
PAINT SKYBLUE (-6325 5625);
FORCEPROP 2 LAST VALUE ISL99390FRZ-TR5935
J 0
(-6325 5825);
DISPLAY 0.489362 (-6325 5825);
PAINT SKYBLUE (-6325 5825);
FORCEPROP 1 LAST PART_NUMBER AL099390004
J 0
(-6325 5700);
DISPLAY 0.489362 (-6325 5700);
PAINT SKYBLUE (-6325 5700);
FORCEPROP 1 LAST CDS_LMAN_SYM_OUTLINE -300,700,250,-650
J 0
(-6025 4900);
DISPLAY 0.468085 (-6025 4900);
PAINT GREEN (-6025 4900);
DISPLAY INVISIBLE (-6025 4900);
FORCEPROP 1 LAST NEEDS_NO_SIZE TRUE
J 0
(-6025 4900);
DISPLAY 0.723404 (-6025 4900);
PAINT GREEN (-6025 4900);
DISPLAY INVISIBLE (-6025 4900);
FORCEPROP 2 LAST CDS_LIB pure_quanta
J 0
(-6025 4900);
DISPLAY INVISIBLE (-6025 4900);
FORCEPROP 1 LAST PATH I122
J 0
(-6025 4900);
DISPLAY 0.723404 (-6025 4900);
PAINT GREEN (-6025 4900);
DISPLAY INVISIBLE (-6025 4900);
FORCEADD ISL99390FRZTR5935..1
(-6000 1800);
FORCEPROP 1 LAST LOCATION PU50
J 0
(-6300 2675);
DISPLAY 0.489362 (-6300 2675);
PAINT SKYBLUE (-6300 2675);
FORCEPROP 0 LAST $SEC 1
J 0
(-6300 2825);
DISPLAY 0.680851 (-6300 2825);
PAINT MONO (-6300 2825);
DISPLAY INVISIBLE (-6300 2825);
FORCEPROP 0 LAST CDS_SEC 1
J 0
(-6300 2825);
DISPLAY 1.021277 (-6300 2825);
DISPLAY INVISIBLE (-6300 2825);
FORCEPROP 0 LASTPIN (-5600 1350) $PN 2
J 0
(-5590 1360);
DISPLAY 0.489362 (-5590 1360);
PAINT MONO (-5590 1360);
FORCEPROP 0 LASTPIN (-5600 2150) $PN 33
J 0
(-5590 2160);
DISPLAY 0.489362 (-5590 2160);
PAINT MONO (-5590 2160);
FORCEPROP 0 LASTPIN (-6450 1550) $PN 31
J 2
(-6460 1560);
DISPLAY 0.489362 (-6460 1560);
PAINT MONO (-6460 1560);
FORCEPROP 0 LASTPIN (-6450 1950) $PN 35
J 2
(-6460 1960);
DISPLAY 0.489362 (-6460 1960);
PAINT MONO (-6460 1960);
FORCEPROP 0 LASTPIN (-5600 1500) $PN 6
J 0
(-5590 1510);
DISPLAY 0.489362 (-5590 1510);
PAINT MONO (-5590 1510);
FORCEPROP 0 LASTPIN (-5600 1450) $PN 41
J 0
(-5590 1460);
DISPLAY 0.489362 (-5590 1460);
PAINT MONO (-5590 1460);
FORCEPROP 0 LASTPIN (-6450 1800) $PN 38
J 2
(-6460 1810);
DISPLAY 0.489362 (-6460 1810);
PAINT MONO (-6460 1810);
FORCEPROP 0 LASTPIN (-6450 1500) $PN 37
J 2
(-6460 1510);
DISPLAY 0.489362 (-6460 1510);
PAINT MONO (-6460 1510);
FORCEPROP 0 LASTPIN (-5600 1300) $PN 5
J 0
(-5590 1310);
DISPLAY 0.489362 (-5590 1310);
PAINT MONO (-5590 1310);
FORCEPROP 0 LASTPIN (-5600 1250) $PN 7_9-20_24
J 0
(-5590 1260);
DISPLAY 0.489362 (-5590 1260);
PAINT MONO (-5590 1260);
FORCEPROP 0 LASTPIN (-5600 1200) $PN 40
J 0
(-5590 1210);
DISPLAY 0.489362 (-5590 1210);
PAINT MONO (-5590 1210);
FORCEPROP 0 LASTPIN (-5600 1900) $PN 32
J 0
(-5590 1910);
DISPLAY 0.489362 (-5590 1910);
PAINT MONO (-5590 1910);
FORCEPROP 0 LASTPIN (-6450 2450) $PN 4
J 2
(-6460 2460);
DISPLAY 0.489362 (-6460 2460);
PAINT MONO (-6460 2460);
FORCEPROP 0 LASTPIN (-6450 1200) $PN 34
J 2
(-6460 1210);
DISPLAY 0.489362 (-6460 1210);
PAINT MONO (-6460 1210);
FORCEPROP 0 LASTPIN (-6450 1700) $PN 39
J 2
(-6460 1710);
DISPLAY 0.489362 (-6460 1710);
PAINT MONO (-6460 1710);
FORCEPROP 0 LASTPIN (-5600 1800) $PN 10_19
J 0
(-5590 1810);
DISPLAY 0.489362 (-5590 1810);
PAINT MONO (-5590 1810);
FORCEPROP 0 LASTPIN (-6450 1300) $PN 36
J 2
(-6460 1310);
DISPLAY 0.489362 (-6460 1310);
PAINT MONO (-6460 1310);
FORCEPROP 0 LASTPIN (-6450 2150) $PN 3
J 2
(-6460 2160);
DISPLAY 0.489362 (-6460 2160);
PAINT MONO (-6460 2160);
FORCEPROP 0 LASTPIN (-5600 2450) $PN 25_29
J 0
(-5590 2460);
DISPLAY 0.489362 (-5590 2460);
PAINT MONO (-5590 2460);
FORCEPROP 0 LASTPIN (-5600 2400) $PN 30
J 0
(-5590 2410);
DISPLAY 0.489362 (-5590 2410);
PAINT MONO (-5590 2410);
FORCEPROP 0 LASTPIN (-5600 1550) $PN 1
J 0
(-5590 1560);
DISPLAY 0.489362 (-5590 1560);
PAINT MONO (-5590 1560);
FORCEPROP 2 LAST PART_TYPE SMLF
J 0
(-6300 2775);
DISPLAY 1.021277 (-6300 2775);
FORCEPROP 1 LAST MATERIAL IC
J 0
(-6300 2525);
DISPLAY 0.489362 (-6300 2525);
PAINT SKYBLUE (-6300 2525);
FORCEPROP 2 LAST VALUE ISL99390FRZ-TR5935
J 0
(-6300 2725);
DISPLAY 0.489362 (-6300 2725);
PAINT SKYBLUE (-6300 2725);
FORCEPROP 1 LAST PART_NUMBER AL099390004
J 0
(-6300 2600);
DISPLAY 0.489362 (-6300 2600);
PAINT SKYBLUE (-6300 2600);
FORCEPROP 1 LAST CDS_LMAN_SYM_OUTLINE -300,700,250,-650
J 0
(-6000 1800);
DISPLAY 0.468085 (-6000 1800);
PAINT GREEN (-6000 1800);
DISPLAY INVISIBLE (-6000 1800);
FORCEPROP 1 LAST NEEDS_NO_SIZE TRUE
J 0
(-6000 1800);
DISPLAY 0.723404 (-6000 1800);
PAINT GREEN (-6000 1800);
DISPLAY INVISIBLE (-6000 1800);
FORCEPROP 2 LAST CDS_LIB pure_quanta
J 0
(-6000 1800);
DISPLAY INVISIBLE (-6000 1800);
FORCEPROP 1 LAST PATH I123
J 0
(-6000 1800);
DISPLAY 0.723404 (-6000 1800);
PAINT GREEN (-6000 1800);
DISPLAY INVISIBLE (-6000 1800);
FORCEADD OFFPAGE..3
(-2200 1550);
FORCEPROP 2 LAST $XR0 174 
J 0
(-1956 1550);
DISPLAY 0.638298 (-1956 1550);
PAINT MONO (-1956 1550);
FORCEPROP 2 LAST PATH I124
J 0
(-2000 1625);
DISPLAY 1.021277 (-2000 1625);
DISPLAY INVISIBLE (-2000 1625);
FORCEPROP 1 LAST COMMENT_BODY TRUE
J 0
(-2250 1450);
DISPLAY 0.872340 (-2250 1450);
PAINT GREEN (-2250 1450);
DISPLAY INVISIBLE (-2250 1450);
FORCEPROP 1 LAST OFFPAGE TRUE
J 0
(-1875 1425);
DISPLAY 0.872340 (-1875 1425);
PAINT GREEN (-1875 1425);
DISPLAY INVISIBLE (-1875 1425);
FORCEPROP 2 LAST CDS_LIB standard
J 0
(-2200 1550);
DISPLAY INVISIBLE (-2200 1550);
FORCEADD Q_CAP..1
(-4675 4650);
FORCEPROP 1 LAST LOCATION PC185
J 0
(-4625 4750);
DISPLAY 0.489362 (-4625 4750);
PAINT SKYBLUE (-4625 4750);
FORCEPROP 0 LAST $SEC 1
J 0
(-4625 4800);
DISPLAY 0.680851 (-4625 4800);
PAINT MONO (-4625 4800);
DISPLAY INVISIBLE (-4625 4800);
FORCEPROP 0 LAST CDS_SEC 1
J 0
(-4625 4800);
DISPLAY 1.021277 (-4625 4800);
DISPLAY INVISIBLE (-4625 4800);
FORCEPROP 1 LASTPIN (-4675 4750) $PN 1
J 0
(-4665 4730);
DISPLAY 0.489362 (-4665 4730);
PAINT MONO (-4665 4730);
FORCEPROP 1 LASTPIN (-4675 4550) $PN 2
J 0
(-4665 4530);
DISPLAY 0.489362 (-4665 4530);
PAINT MONO (-4665 4530);
FORCEPROP 1 LAST PART_NUMBER CH1566K1B09
J 0
(-4625 4500);
DISPLAY 0.489362 (-4625 4500);
PAINT SKYBLUE (-4625 4500);
FORCEPROP 1 LAST TOLERANCE 10%
J 0
(-4625 4600);
DISPLAY 0.489362 (-4625 4600);
PAINT SKYBLUE (-4625 4600);
FORCEPROP 1 LAST MATERIAL EMPTY
J 0
(-4625 4550);
DISPLAY 0.489362 (-4625 4550);
PAINT RED (-4625 4550);
FORCEPROP 1 LAST PACK_TYPE C0402
J 0
(-4625 4450);
DISPLAY 0.489362 (-4625 4450);
PAINT SKYBLUE (-4625 4450);
FORCEPROP 1 LAST VALUE 560PF
J 0
(-4625 4700);
DISPLAY 0.489362 (-4625 4700);
PAINT SKYBLUE (-4625 4700);
FORCEPROP 1 LAST VOLTAGE 50V
J 0
(-4625 4650);
DISPLAY 0.489362 (-4625 4650);
PAINT SKYBLUE (-4625 4650);
FORCEPROP 2 LAST CDS_LIB pure_quanta
J 0
(-4675 4650);
DISPLAY INVISIBLE (-4675 4650);
FORCEPROP 1 LAST PATH I125
J 0
(-4625 4800);
DISPLAY 0.978723 (-4625 4800);
PAINT WHITE (-4625 4800);
DISPLAY INVISIBLE (-4625 4800);
FORCEADD Q_RES..2
(-4675 4200);
FORCEPROP 1 LAST LOCATION PR502
J 0
(-4630 4300);
DISPLAY 0.489362 (-4630 4300);
PAINT SKYBLUE (-4630 4300);
FORCEPROP 0 LAST $SEC 1
J 0
(-4625 4375);
DISPLAY 0.680851 (-4625 4375);
PAINT MONO (-4625 4375);
DISPLAY INVISIBLE (-4625 4375);
FORCEPROP 0 LAST CDS_SEC 1
J 0
(-4625 4375);
DISPLAY 1.021277 (-4625 4375);
DISPLAY INVISIBLE (-4625 4375);
FORCEPROP 1 LASTPIN (-4675 4300) $PN 1
J 0
(-4670 4262);
DISPLAY 0.489362 (-4670 4262);
PAINT MONO (-4670 4262);
FORCEPROP 1 LASTPIN (-4675 4100) $PN 2
J 0
(-4670 4110);
DISPLAY 0.489362 (-4670 4110);
PAINT MONO (-4670 4110);
FORCEPROP 1 LAST WATTAGE 1/8W
J 0
(-4635 4150);
DISPLAY 0.489362 (-4635 4150);
PAINT SKYBLUE (-4635 4150);
FORCEPROP 1 LAST MATERIAL EMPTY
J 0
(-4635 4100);
DISPLAY 0.489362 (-4635 4100);
PAINT RED (-4635 4100);
FORCEPROP 1 LAST TOLERANCE 1%
J 0
(-4630 4225);
DISPLAY 0.489362 (-4630 4225);
PAINT SKYBLUE (-4630 4225);
FORCEPROP 1 LAST VALUE 1.5
J 0
(-4630 4250);
DISPLAY 0.489362 (-4630 4250);
PAINT SKYBLUE (-4630 4250);
FORCEPROP 1 LAST PART_NUMBER CS-1504FB00
J 0
(-4635 4050);
DISPLAY 0.489362 (-4635 4050);
PAINT SKYBLUE (-4635 4050);
FORCEPROP 1 LAST PACK_TYPE 0402LF
J 0
(-4635 4000);
DISPLAY 0.489362 (-4635 4000);
PAINT SKYBLUE (-4635 4000);
FORCEPROP 2 LAST CDS_LIB pure_quanta
J 0
(-4675 4200);
DISPLAY INVISIBLE (-4675 4200);
FORCEPROP 1 LAST PATH I126
J 0
(-4625 4375);
DISPLAY 0.978723 (-4625 4375);
PAINT WHITE (-4625 4375);
DISPLAY INVISIBLE (-4625 4375);
FORCEADD UNIVERSAL_GND..1
(-4675 3950);
FORCEPROP 3 LASTPIN (-4675 4000) SIG_NAME GND\g
J 0
(-4665 4010);
DISPLAY 0.659574 (-4665 4010);
PAINT MONO (-4665 4010);
DISPLAY INVISIBLE (-4665 4010);
FORCEPROP 2 LAST CDS_LIB pure_quanta_power
J 0
(-4675 3950);
DISPLAY INVISIBLE (-4675 3950);
FORCEPROP 1 LAST PATH I127
J 0
(-4600 3950);
DISPLAY 0.872340 (-4600 3950);
PAINT AQUA (-4600 3950);
DISPLAY INVISIBLE (-4600 3950);
FORCEPROP 1 LAST HDL_POWER GND
J 1
(-4650 3875);
DISPLAY 0.872340 (-4650 3875);
PAINT GREEN (-4650 3875);
DISPLAY INVISIBLE (-4650 3875);
FORCEADD Q_CAP..1
(-4700 1625);
FORCEPROP 1 LAST LOCATION PC187
J 0
(-4650 1725);
DISPLAY 0.489362 (-4650 1725);
PAINT SKYBLUE (-4650 1725);
FORCEPROP 0 LAST $SEC 1
J 0
(-4650 1775);
DISPLAY 0.680851 (-4650 1775);
PAINT MONO (-4650 1775);
DISPLAY INVISIBLE (-4650 1775);
FORCEPROP 0 LAST CDS_SEC 1
J 0
(-4650 1775);
DISPLAY 1.021277 (-4650 1775);
DISPLAY INVISIBLE (-4650 1775);
FORCEPROP 1 LASTPIN (-4700 1725) $PN 1
J 0
(-4690 1705);
DISPLAY 0.489362 (-4690 1705);
PAINT MONO (-4690 1705);
FORCEPROP 1 LASTPIN (-4700 1525) $PN 2
J 0
(-4690 1505);
DISPLAY 0.489362 (-4690 1505);
PAINT MONO (-4690 1505);
FORCEPROP 1 LAST MATERIAL EMPTY
J 0
(-4650 1525);
DISPLAY 0.489362 (-4650 1525);
PAINT RED (-4650 1525);
FORCEPROP 1 LAST TOLERANCE 10%
J 0
(-4650 1575);
DISPLAY 0.489362 (-4650 1575);
PAINT SKYBLUE (-4650 1575);
FORCEPROP 1 LAST VALUE 560PF
J 0
(-4650 1675);
DISPLAY 0.489362 (-4650 1675);
PAINT SKYBLUE (-4650 1675);
FORCEPROP 1 LAST PART_NUMBER CH1566K1B09
J 0
(-4650 1475);
DISPLAY 0.489362 (-4650 1475);
PAINT SKYBLUE (-4650 1475);
FORCEPROP 1 LAST VOLTAGE 50V
J 0
(-4650 1625);
DISPLAY 0.489362 (-4650 1625);
PAINT SKYBLUE (-4650 1625);
FORCEPROP 1 LAST PACK_TYPE C0402
J 0
(-4650 1425);
DISPLAY 0.489362 (-4650 1425);
PAINT SKYBLUE (-4650 1425);
FORCEPROP 2 LAST CDS_LIB pure_quanta
J 0
(-4700 1625);
DISPLAY INVISIBLE (-4700 1625);
FORCEPROP 1 LAST PATH I128
J 0
(-4650 1775);
DISPLAY 0.978723 (-4650 1775);
PAINT WHITE (-4650 1775);
DISPLAY INVISIBLE (-4650 1775);
FORCEADD Q_RES..2
(-4700 1125);
FORCEPROP 1 LAST LOCATION PR503
J 0
(-4655 1250);
DISPLAY 0.489362 (-4655 1250);
PAINT SKYBLUE (-4655 1250);
FORCEPROP 0 LAST $SEC 1
J 0
(-4650 1300);
DISPLAY 0.680851 (-4650 1300);
PAINT MONO (-4650 1300);
DISPLAY INVISIBLE (-4650 1300);
FORCEPROP 0 LAST CDS_SEC 1
J 0
(-4650 1300);
DISPLAY 1.021277 (-4650 1300);
DISPLAY INVISIBLE (-4650 1300);
FORCEPROP 1 LASTPIN (-4700 1225) $PN 1
J 0
(-4695 1187);
DISPLAY 0.489362 (-4695 1187);
PAINT MONO (-4695 1187);
FORCEPROP 1 LASTPIN (-4700 1025) $PN 2
J 0
(-4695 1035);
DISPLAY 0.489362 (-4695 1035);
PAINT MONO (-4695 1035);
FORCEPROP 1 LAST WATTAGE 1/8W
J 0
(-4660 1100);
DISPLAY 0.489362 (-4660 1100);
PAINT SKYBLUE (-4660 1100);
FORCEPROP 1 LAST MATERIAL EMPTY
J 0
(-4660 1050);
DISPLAY 0.489362 (-4660 1050);
PAINT RED (-4660 1050);
FORCEPROP 1 LAST TOLERANCE 1%
J 0
(-4655 1150);
DISPLAY 0.489362 (-4655 1150);
PAINT SKYBLUE (-4655 1150);
FORCEPROP 1 LAST VALUE 1.5
J 0
(-4655 1200);
DISPLAY 0.489362 (-4655 1200);
PAINT SKYBLUE (-4655 1200);
FORCEPROP 1 LAST PART_NUMBER CS-1504FB00
J 0
(-4660 1000);
DISPLAY 0.489362 (-4660 1000);
PAINT SKYBLUE (-4660 1000);
FORCEPROP 1 LAST PACK_TYPE 0402LF
J 0
(-4660 950);
DISPLAY 0.489362 (-4660 950);
PAINT SKYBLUE (-4660 950);
FORCEPROP 2 LAST CDS_LIB pure_quanta
J 0
(-4700 1125);
DISPLAY INVISIBLE (-4700 1125);
FORCEPROP 1 LAST PATH I129
J 0
(-4650 1300);
DISPLAY 0.978723 (-4650 1300);
PAINT WHITE (-4650 1300);
DISPLAY INVISIBLE (-4650 1300);
FORCEADD UNIVERSAL_GND..1
(-4700 900);
FORCEPROP 3 LASTPIN (-4700 950) SIG_NAME GND\g
J 0
(-4690 960);
DISPLAY 0.659574 (-4690 960);
PAINT MONO (-4690 960);
DISPLAY INVISIBLE (-4690 960);
FORCEPROP 2 LAST CDS_LIB pure_quanta_power
J 0
(-4700 900);
DISPLAY INVISIBLE (-4700 900);
FORCEPROP 1 LAST PATH I130
J 0
(-4625 900);
DISPLAY 0.872340 (-4625 900);
PAINT AQUA (-4625 900);
DISPLAY INVISIBLE (-4625 900);
FORCEPROP 1 LAST HDL_POWER GND
J 1
(-4675 825);
DISPLAY 0.872340 (-4675 825);
PAINT GREEN (-4675 825);
DISPLAY INVISIBLE (-4675 825);
FORCEADD VCC_CORE..1
(-7525 6150);
FORCEPROP 3 LASTPIN (-7525 6100) SIG_NAME PVDDCR_CPU0_P0_PVCC\g
J 0
(-7515 6110);
DISPLAY 0.659574 (-7515 6110);
PAINT MONO (-7515 6110);
DISPLAY INVISIBLE (-7515 6110);
FORCEPROP 1 LAST HDL_POWER PVDDCR_CPU0_P0_PVCC
J 1
(-7525 6200);
DISPLAY 0.489362 (-7525 6200);
PAINT GREEN (-7525 6200);
FORCEPROP 2 LAST CDS_LIB pure_quanta_power
J 0
(-7525 6150);
DISPLAY INVISIBLE (-7525 6150);
FORCEPROP 1 LAST PATH I131
J 0
(-7475 6175);
DISPLAY 0.872340 (-7475 6175);
PAINT AQUA (-7475 6175);
DISPLAY INVISIBLE (-7475 6175);
FORCEADD VCC_CORE..1
(-7500 3075);
FORCEPROP 3 LASTPIN (-7500 3025) SIG_NAME PVDDCR_CPU0_P0_PVCC\g
J 0
(-7490 3035);
DISPLAY 0.659574 (-7490 3035);
PAINT MONO (-7490 3035);
DISPLAY INVISIBLE (-7490 3035);
FORCEPROP 1 LAST HDL_POWER PVDDCR_CPU0_P0_PVCC
J 1
(-7500 3125);
DISPLAY 0.489362 (-7500 3125);
PAINT GREEN (-7500 3125);
FORCEPROP 2 LAST CDS_LIB pure_quanta_power
J 0
(-7500 3075);
DISPLAY INVISIBLE (-7500 3075);
FORCEPROP 1 LAST PATH I132
J 0
(-7450 3100);
DISPLAY 0.872340 (-7450 3100);
PAINT AQUA (-7450 3100);
DISPLAY INVISIBLE (-7450 3100);
FORCEADD Q_RES..2
(-550 4700);
FORCEPROP 1 LAST LOCATION PR334
J 0
(-505 4825);
DISPLAY 0.489362 (-505 4825);
PAINT SKYBLUE (-505 4825);
FORCEPROP 0 LAST $SEC 1
J 0
(-500 4850);
DISPLAY 0.680851 (-500 4850);
PAINT MONO (-500 4850);
DISPLAY INVISIBLE (-500 4850);
FORCEPROP 0 LAST CDS_SEC 1
J 0
(-500 4850);
DISPLAY 1.021277 (-500 4850);
DISPLAY INVISIBLE (-500 4850);
FORCEPROP 1 LASTPIN (-550 4800) $PN 1
J 0
(-545 4762);
DISPLAY 0.787234 (-545 4762);
PAINT MONO (-545 4762);
DISPLAY INVISIBLE (-545 4762);
FORCEPROP 1 LASTPIN (-550 4600) $PN 2
J 0
(-545 4610);
DISPLAY 0.787234 (-545 4610);
PAINT MONO (-545 4610);
DISPLAY INVISIBLE (-545 4610);
FORCEPROP 1 LAST WATTAGE 1/16W
J 0
(-510 4675);
DISPLAY 0.489362 (-510 4675);
PAINT SKYBLUE (-510 4675);
FORCEPROP 1 LAST MATERIAL CHIP
J 0
(-510 4625);
DISPLAY 0.489362 (-510 4625);
PAINT SKYBLUE (-510 4625);
FORCEPROP 1 LAST TOLERANCE 1%
J 0
(-505 4725);
DISPLAY 0.489362 (-505 4725);
PAINT SKYBLUE (-505 4725);
FORCEPROP 1 LAST VALUE 1K
J 0
(-505 4775);
DISPLAY 0.489362 (-505 4775);
PAINT SKYBLUE (-505 4775);
FORCEPROP 1 LAST PART_NUMBER TMP_QCS21002FB24
J 0
(-510 4575);
DISPLAY 0.489362 (-510 4575);
PAINT SKYBLUE (-510 4575);
FORCEPROP 1 LAST PACK_TYPE 0402LF
J 0
(-510 4525);
DISPLAY 0.489362 (-510 4525);
PAINT SKYBLUE (-510 4525);
FORCEPROP 2 LAST CDS_LIB pure_quanta
J 0
(-550 4700);
DISPLAY INVISIBLE (-550 4700);
FORCEPROP 1 LAST PATH I133
J 0
(-500 4875);
DISPLAY 0.978723 (-500 4875);
PAINT WHITE (-500 4875);
DISPLAY INVISIBLE (-500 4875);
FORCEADD Q_CAP..1
(-3800 5750);
FORCEPROP 1 LAST LOCATION PC593_1
J 0
(-3750 5850);
DISPLAY 0.489362 (-3750 5850);
PAINT SKYBLUE (-3750 5850);
FORCEPROP 0 LAST $SEC 1
J 0
(-3750 5875);
DISPLAY 0.680851 (-3750 5875);
PAINT MONO (-3750 5875);
DISPLAY INVISIBLE (-3750 5875);
FORCEPROP 0 LAST CDS_SEC 1
J 0
(-3750 5875);
DISPLAY 0.680851 (-3750 5875);
DISPLAY INVISIBLE (-3750 5875);
FORCEPROP 1 LASTPIN (-3800 5850) $PN 1
J 0
(-3790 5830);
DISPLAY 0.787234 (-3790 5830);
PAINT MONO (-3790 5830);
DISPLAY INVISIBLE (-3790 5830);
FORCEPROP 1 LASTPIN (-3800 5650) $PN 2
J 0
(-3790 5630);
DISPLAY 0.787234 (-3790 5630);
PAINT MONO (-3790 5630);
DISPLAY INVISIBLE (-3790 5630);
FORCEPROP 1 LAST MATERIAL X6S
J 0
(-3750 5650);
DISPLAY 0.489362 (-3750 5650);
PAINT SKYBLUE (-3750 5650);
FORCEPROP 1 LAST TOLERANCE 10%
J 0
(-3750 5700);
DISPLAY 0.489362 (-3750 5700);
PAINT SKYBLUE (-3750 5700);
FORCEPROP 1 LAST VALUE 10UF
J 0
(-3750 5800);
DISPLAY 0.489362 (-3750 5800);
PAINT SKYBLUE (-3750 5800);
FORCEPROP 1 LAST PART_NUMBER CH6104KEA00
J 0
(-3750 5600);
DISPLAY 0.489362 (-3750 5600);
PAINT SKYBLUE (-3750 5600);
FORCEPROP 1 LAST VOLTAGE 25V
J 0
(-3750 5750);
DISPLAY 0.489362 (-3750 5750);
PAINT SKYBLUE (-3750 5750);
FORCEPROP 1 LAST PACK_TYPE C0805
J 0
(-3750 5550);
DISPLAY 0.489362 (-3750 5550);
PAINT SKYBLUE (-3750 5550);
FORCEPROP 2 LAST CDS_LIB pure_quanta
J 0
(-3800 5750);
DISPLAY INVISIBLE (-3800 5750);
FORCEPROP 1 LAST PATH I134
J 0
(-3750 5900);
DISPLAY 0.978723 (-3750 5900);
PAINT WHITE (-3750 5900);
DISPLAY INVISIBLE (-3750 5900);
FORCEADD Q_CAP..1
(-3600 2700);
FORCEPROP 1 LAST LOCATION PC595_2
J 0
(-3550 2800);
DISPLAY 0.489362 (-3550 2800);
PAINT SKYBLUE (-3550 2800);
FORCEPROP 0 LAST $SEC 1
J 0
(-3550 2825);
DISPLAY 0.680851 (-3550 2825);
PAINT MONO (-3550 2825);
DISPLAY INVISIBLE (-3550 2825);
FORCEPROP 0 LAST CDS_SEC 1
J 0
(-3550 2825);
DISPLAY 0.680851 (-3550 2825);
DISPLAY INVISIBLE (-3550 2825);
FORCEPROP 1 LASTPIN (-3600 2800) $PN 1
J 0
(-3590 2780);
DISPLAY 0.787234 (-3590 2780);
PAINT MONO (-3590 2780);
DISPLAY INVISIBLE (-3590 2780);
FORCEPROP 1 LASTPIN (-3600 2600) $PN 2
J 0
(-3590 2580);
DISPLAY 0.787234 (-3590 2580);
PAINT MONO (-3590 2580);
DISPLAY INVISIBLE (-3590 2580);
FORCEPROP 1 LAST MATERIAL X6S
J 0
(-3550 2600);
DISPLAY 0.489362 (-3550 2600);
PAINT SKYBLUE (-3550 2600);
FORCEPROP 1 LAST TOLERANCE 10%
J 0
(-3550 2650);
DISPLAY 0.489362 (-3550 2650);
PAINT SKYBLUE (-3550 2650);
FORCEPROP 1 LAST VALUE 10UF
J 0
(-3550 2750);
DISPLAY 0.489362 (-3550 2750);
PAINT SKYBLUE (-3550 2750);
FORCEPROP 1 LAST PART_NUMBER CH6104KEA00
J 0
(-3550 2550);
DISPLAY 0.489362 (-3550 2550);
PAINT SKYBLUE (-3550 2550);
FORCEPROP 1 LAST VOLTAGE 25V
J 0
(-3550 2700);
DISPLAY 0.489362 (-3550 2700);
PAINT SKYBLUE (-3550 2700);
FORCEPROP 1 LAST PACK_TYPE C0805
J 0
(-3550 2500);
DISPLAY 0.489362 (-3550 2500);
PAINT SKYBLUE (-3550 2500);
FORCEPROP 2 LAST CDS_LIB pure_quanta
J 0
(-3600 2700);
DISPLAY INVISIBLE (-3600 2700);
FORCEPROP 1 LAST PATH I135
J 0
(-3550 2850);
DISPLAY 0.978723 (-3550 2850);
PAINT WHITE (-3550 2850);
DISPLAY INVISIBLE (-3550 2850);
FORCEADD OFFPAGE..3
R 2
(-4000 4650);
FORCEPROP 2 LAST $XR0 174 
J 0
(-4310 4650);
DISPLAY 0.638298 (-4310 4650);
PAINT MONO (-4310 4650);
FORCEPROP 2 LAST PATH I136
J 0
(-4275 4700);
DISPLAY 1.021277 (-4275 4700);
DISPLAY INVISIBLE (-4275 4700);
FORCEPROP 2 LAST CDS_LIB standard
J 2
(-4000 4650);
DISPLAY INVISIBLE (-4000 4650);
FORCEPROP 1 LAST OFFPAGE TRUE
J 2
(-4325 4525);
DISPLAY 0.872340 (-4325 4525);
PAINT GREEN (-4325 4525);
DISPLAY INVISIBLE (-4325 4525);
FORCEPROP 1 LAST COMMENT_BODY TRUE
J 2
(-3950 4550);
DISPLAY 0.872340 (-3950 4550);
PAINT GREEN (-3950 4550);
DISPLAY INVISIBLE (-3950 4550);
FORCEADD UNIVERSAL_GND..1
(-2225 4500);
FORCEPROP 3 LASTPIN (-2225 4550) SIG_NAME GND\g
J 0
(-2215 4560);
DISPLAY 0.659574 (-2215 4560);
PAINT MONO (-2215 4560);
DISPLAY INVISIBLE (-2215 4560);
FORCEPROP 2 LAST CDS_LIB pure_quanta_power
J 0
(-2225 4500);
DISPLAY INVISIBLE (-2225 4500);
FORCEPROP 1 LAST PATH I137
J 0
(-2150 4500);
DISPLAY 0.872340 (-2150 4500);
PAINT AQUA (-2150 4500);
DISPLAY INVISIBLE (-2150 4500);
FORCEPROP 1 LAST HDL_POWER GND
J 1
(-2200 4425);
DISPLAY 0.872340 (-2200 4425);
PAINT GREEN (-2200 4425);
DISPLAY INVISIBLE (-2200 4425);
FORCEADD Q_RES..1
(-7200 4600);
FORCEPROP 1 LAST LOCATION PR358
J 0
(-7225 4650);
DISPLAY 0.489362 (-7225 4650);
PAINT SKYBLUE (-7225 4650);
FORCEPROP 0 LAST $SEC 1
J 0
(-7200 4675);
DISPLAY 0.680851 (-7200 4675);
PAINT MONO (-7200 4675);
DISPLAY INVISIBLE (-7200 4675);
FORCEPROP 0 LAST CDS_SEC 1
J 0
(-7200 4675);
DISPLAY 1.021277 (-7200 4675);
DISPLAY INVISIBLE (-7200 4675);
FORCEPROP 1 LASTPIN (-7300 4600) $PN 1
J 0
(-7288 4612);
DISPLAY 0.489362 (-7288 4612);
PAINT MONO (-7288 4612);
FORCEPROP 1 LASTPIN (-7100 4600) $PN 2
J 0
(-7138 4612);
DISPLAY 0.489362 (-7138 4612);
PAINT MONO (-7138 4612);
FORCEPROP 1 LAST WATTAGE 1/16W
J 0
(-7100 4500);
DISPLAY 0.489362 (-7100 4500);
PAINT SKYBLUE (-7100 4500);
FORCEPROP 1 LAST MATERIAL EMPTY
J 0
(-7500 4500);
DISPLAY 0.489362 (-7500 4500);
PAINT RED (-7500 4500);
FORCEPROP 1 LAST TOLERANCE 1%
J 0
(-7075 4625);
DISPLAY 0.489362 (-7075 4625);
PAINT SKYBLUE (-7075 4625);
FORCEPROP 1 LAST VALUE 8.87K
J 2
(-7325 4625);
DISPLAY 0.489362 (-7325 4625);
PAINT SKYBLUE (-7325 4625);
FORCEPROP 1 LAST PART_NUMBER CS28872FB01
J 0
(-7500 4550);
DISPLAY 0.489362 (-7500 4550);
PAINT SKYBLUE (-7500 4550);
FORCEPROP 1 LAST PACK_TYPE 0402LF
J 0
(-7100 4550);
DISPLAY 0.489362 (-7100 4550);
PAINT SKYBLUE (-7100 4550);
FORCEPROP 2 LAST CDS_LIB pure_quanta
J 0
(-7200 4600);
DISPLAY INVISIBLE (-7200 4600);
FORCEPROP 1 LAST PATH I15
J 0
(-7250 4750);
DISPLAY 0.978723 (-7250 4750);
PAINT WHITE (-7250 4750);
DISPLAY INVISIBLE (-7250 4750);
FORCEADD Q_RES..1
(-4725 5250);
FORCEPROP 1 LAST LOCATION PR360
J 0
(-4750 5300);
DISPLAY 0.489362 (-4750 5300);
PAINT SKYBLUE (-4750 5300);
FORCEPROP 0 LAST $SEC 1
J 0
(-4700 5325);
DISPLAY 0.680851 (-4700 5325);
PAINT MONO (-4700 5325);
DISPLAY INVISIBLE (-4700 5325);
FORCEPROP 0 LAST CDS_SEC 1
J 0
(-4700 5325);
DISPLAY 1.021277 (-4700 5325);
DISPLAY INVISIBLE (-4700 5325);
FORCEPROP 1 LASTPIN (-4825 5250) $PN 1
J 0
(-4813 5262);
DISPLAY 0.489362 (-4813 5262);
PAINT MONO (-4813 5262);
FORCEPROP 1 LASTPIN (-4625 5250) $PN 2
J 0
(-4663 5262);
DISPLAY 0.489362 (-4663 5262);
PAINT MONO (-4663 5262);
FORCEPROP 1 LAST PACK_TYPE 0402LF
J 0
(-4625 5150);
DISPLAY 0.489362 (-4625 5150);
PAINT SKYBLUE (-4625 5150);
FORCEPROP 1 LAST TOLERANCE 1%
J 0
(-4625 5275);
DISPLAY 0.489362 (-4625 5275);
PAINT SKYBLUE (-4625 5275);
FORCEPROP 1 LAST MATERIAL CHIP
J 0
(-4975 5150);
DISPLAY 0.489362 (-4975 5150);
PAINT SKYBLUE (-4975 5150);
FORCEPROP 1 LAST WATTAGE 1/16W
J 0
(-4625 5200);
DISPLAY 0.489362 (-4625 5200);
PAINT SKYBLUE (-4625 5200);
FORCEPROP 1 LAST VALUE 4.7
J 2
(-4825 5275);
DISPLAY 0.489362 (-4825 5275);
PAINT SKYBLUE (-4825 5275);
FORCEPROP 1 LAST PART_NUMBER CS-4702FB19
J 0
(-4975 5200);
DISPLAY 0.489362 (-4975 5200);
PAINT SKYBLUE (-4975 5200);
FORCEPROP 1 LAST PATH I19
J 0
(-4775 5400);
DISPLAY 0.978723 (-4775 5400);
PAINT WHITE (-4775 5400);
DISPLAY INVISIBLE (-4775 5400);
FORCEPROP 2 LAST CDS_LIB pure_quanta
J 0
(-4725 5250);
DISPLAY INVISIBLE (-4725 5250);
FORCEADD UNIVERSAL_GND..1
(-5450 4175);
FORCEPROP 3 LASTPIN (-5450 4225) SIG_NAME GND\g
J 0
(-5440 4235);
DISPLAY 0.659574 (-5440 4235);
PAINT MONO (-5440 4235);
DISPLAY INVISIBLE (-5440 4235);
FORCEPROP 2 LAST CDS_LIB pure_quanta_power
J 0
(-5450 4175);
DISPLAY INVISIBLE (-5450 4175);
FORCEPROP 1 LAST PATH I2
J 0
(-5375 4175);
DISPLAY 0.872340 (-5375 4175);
PAINT AQUA (-5375 4175);
DISPLAY INVISIBLE (-5375 4175);
FORCEPROP 1 LAST HDL_POWER GND
J 1
(-5425 4100);
DISPLAY 0.872340 (-5425 4100);
PAINT GREEN (-5425 4100);
DISPLAY INVISIBLE (-5425 4100);
FORCEADD Q_RES..1
(-4200 3725);
FORCEPROP 1 LAST LOCATION PR362
J 0
(-4250 3775);
DISPLAY 0.489362 (-4250 3775);
PAINT SKYBLUE (-4250 3775);
FORCEPROP 0 LAST $SEC 1
J 0
(-4200 3800);
DISPLAY 0.680851 (-4200 3800);
PAINT MONO (-4200 3800);
DISPLAY INVISIBLE (-4200 3800);
FORCEPROP 0 LAST CDS_SEC 1
J 0
(-4200 3800);
DISPLAY 1.021277 (-4200 3800);
DISPLAY INVISIBLE (-4200 3800);
FORCEPROP 1 LASTPIN (-4300 3725) $PN 1
J 0
(-4288 3737);
DISPLAY 0.489362 (-4288 3737);
PAINT MONO (-4288 3737);
FORCEPROP 1 LASTPIN (-4100 3725) $PN 2
J 0
(-4138 3737);
DISPLAY 0.489362 (-4138 3737);
PAINT MONO (-4138 3737);
FORCEPROP 1 LAST WATTAGE 1/16W
J 0
(-4100 3675);
DISPLAY 0.489362 (-4100 3675);
PAINT SKYBLUE (-4100 3675);
FORCEPROP 1 LAST MATERIAL CHIP
J 0
(-4450 3625);
DISPLAY 0.489362 (-4450 3625);
PAINT SKYBLUE (-4450 3625);
FORCEPROP 1 LAST TOLERANCE 5%
J 0
(-4075 3750);
DISPLAY 0.489362 (-4075 3750);
PAINT SKYBLUE (-4075 3750);
FORCEPROP 1 LAST VALUE 0
J 2
(-4325 3750);
DISPLAY 0.489362 (-4325 3750);
PAINT SKYBLUE (-4325 3750);
FORCEPROP 1 LAST PART_NUMBER CS00002JB38
J 0
(-4450 3675);
DISPLAY 0.489362 (-4450 3675);
PAINT SKYBLUE (-4450 3675);
FORCEPROP 1 LAST PACK_TYPE 0402LF
J 0
(-4100 3625);
DISPLAY 0.489362 (-4100 3625);
PAINT SKYBLUE (-4100 3625);
FORCEPROP 2 LAST CDS_LIB pure_quanta
J 0
(-4200 3725);
DISPLAY INVISIBLE (-4200 3725);
FORCEPROP 1 LAST PATH I22
J 0
(-4250 3875);
DISPLAY 0.978723 (-4250 3875);
PAINT WHITE (-4250 3875);
DISPLAY INVISIBLE (-4250 3875);
FORCEADD Q_CAP..1
(-5100 5750);
FORCEPROP 1 LAST LOCATION PC585_1
J 0
(-5050 5850);
DISPLAY 0.489362 (-5050 5850);
PAINT SKYBLUE (-5050 5850);
FORCEPROP 0 LAST $SEC 1
J 0
(-5050 5875);
DISPLAY 0.680851 (-5050 5875);
PAINT MONO (-5050 5875);
DISPLAY INVISIBLE (-5050 5875);
FORCEPROP 0 LAST CDS_SEC 1
J 0
(-5050 5875);
DISPLAY 1.021277 (-5050 5875);
DISPLAY INVISIBLE (-5050 5875);
FORCEPROP 1 LASTPIN (-5100 5850) $PN 1
J 0
(-5090 5830);
DISPLAY 0.489362 (-5090 5830);
PAINT MONO (-5090 5830);
FORCEPROP 1 LASTPIN (-5100 5650) $PN 2
J 0
(-5090 5630);
DISPLAY 0.489362 (-5090 5630);
PAINT MONO (-5090 5630);
FORCEPROP 1 LAST MATERIAL X6S
J 0
(-5050 5650);
DISPLAY 0.489362 (-5050 5650);
PAINT SKYBLUE (-5050 5650);
FORCEPROP 1 LAST TOLERANCE 10%
J 0
(-5050 5700);
DISPLAY 0.489362 (-5050 5700);
PAINT SKYBLUE (-5050 5700);
FORCEPROP 1 LAST VALUE 1UF
J 0
(-5050 5800);
DISPLAY 0.489362 (-5050 5800);
PAINT SKYBLUE (-5050 5800);
FORCEPROP 1 LAST VOLTAGE 25V
J 0
(-5050 5750);
DISPLAY 0.489362 (-5050 5750);
PAINT SKYBLUE (-5050 5750);
FORCEPROP 1 LAST PACK_TYPE C0402
J 0
(-5050 5550);
DISPLAY 0.489362 (-5050 5550);
PAINT SKYBLUE (-5050 5550);
FORCEPROP 1 LAST PART_NUMBER CH5104KEB02
J 0
(-5050 5600);
DISPLAY 0.489362 (-5050 5600);
PAINT SKYBLUE (-5050 5600);
FORCEPROP 2 LAST CDS_LIB pure_quanta
J 0
(-5100 5750);
DISPLAY INVISIBLE (-5100 5750);
FORCEPROP 1 LAST PATH I23
J 0
(-5050 5900);
DISPLAY 0.978723 (-5050 5900);
PAINT WHITE (-5050 5900);
DISPLAY INVISIBLE (-5050 5900);
FORCEADD Q_CAP..1
(-4775 5750);
FORCEPROP 1 LAST LOCATION PC587_1
J 0
(-4725 5850);
DISPLAY 0.489362 (-4725 5850);
PAINT SKYBLUE (-4725 5850);
FORCEPROP 0 LAST $SEC 1
J 0
(-4725 5875);
DISPLAY 0.680851 (-4725 5875);
PAINT MONO (-4725 5875);
DISPLAY INVISIBLE (-4725 5875);
FORCEPROP 0 LAST CDS_SEC 1
J 0
(-4725 5875);
DISPLAY 1.021277 (-4725 5875);
DISPLAY INVISIBLE (-4725 5875);
FORCEPROP 1 LASTPIN (-4775 5850) $PN 1
J 0
(-4765 5830);
DISPLAY 0.489362 (-4765 5830);
PAINT MONO (-4765 5830);
FORCEPROP 1 LASTPIN (-4775 5650) $PN 2
J 0
(-4765 5630);
DISPLAY 0.489362 (-4765 5630);
PAINT MONO (-4765 5630);
FORCEPROP 1 LAST MATERIAL X6S
J 0
(-4725 5650);
DISPLAY 0.489362 (-4725 5650);
PAINT SKYBLUE (-4725 5650);
FORCEPROP 1 LAST VALUE 10UF
J 0
(-4725 5800);
DISPLAY 0.489362 (-4725 5800);
PAINT SKYBLUE (-4725 5800);
FORCEPROP 1 LAST PART_NUMBER CH6104KEA00
J 0
(-4725 5600);
DISPLAY 0.489362 (-4725 5600);
PAINT SKYBLUE (-4725 5600);
FORCEPROP 1 LAST VOLTAGE 25V
J 0
(-4725 5750);
DISPLAY 0.489362 (-4725 5750);
PAINT SKYBLUE (-4725 5750);
FORCEPROP 1 LAST PACK_TYPE C0805
J 0
(-4725 5550);
DISPLAY 0.489362 (-4725 5550);
PAINT SKYBLUE (-4725 5550);
FORCEPROP 1 LAST TOLERANCE 10%
J 0
(-4725 5700);
DISPLAY 0.489362 (-4725 5700);
PAINT SKYBLUE (-4725 5700);
FORCEPROP 2 LAST CDS_LIB pure_quanta
J 0
(-4775 5750);
DISPLAY INVISIBLE (-4775 5750);
FORCEPROP 1 LAST PATH I24
J 0
(-4725 5900);
DISPLAY 0.978723 (-4725 5900);
PAINT WHITE (-4725 5900);
DISPLAY INVISIBLE (-4725 5900);
FORCEADD Q_CAP..1
(-4450 5750);
FORCEPROP 1 LAST LOCATION PC589_1
J 0
(-4400 5850);
DISPLAY 0.489362 (-4400 5850);
PAINT SKYBLUE (-4400 5850);
FORCEPROP 0 LAST $SEC 1
J 0
(-4400 5875);
DISPLAY 0.680851 (-4400 5875);
PAINT MONO (-4400 5875);
DISPLAY INVISIBLE (-4400 5875);
FORCEPROP 0 LAST CDS_SEC 1
J 0
(-4400 5875);
DISPLAY 1.021277 (-4400 5875);
DISPLAY INVISIBLE (-4400 5875);
FORCEPROP 1 LASTPIN (-4450 5850) $PN 1
J 0
(-4440 5830);
DISPLAY 0.489362 (-4440 5830);
PAINT MONO (-4440 5830);
FORCEPROP 1 LASTPIN (-4450 5650) $PN 2
J 0
(-4440 5630);
DISPLAY 0.489362 (-4440 5630);
PAINT MONO (-4440 5630);
FORCEPROP 1 LAST MATERIAL X6S
J 0
(-4400 5650);
DISPLAY 0.489362 (-4400 5650);
PAINT SKYBLUE (-4400 5650);
FORCEPROP 1 LAST TOLERANCE 10%
J 0
(-4400 5700);
DISPLAY 0.489362 (-4400 5700);
PAINT SKYBLUE (-4400 5700);
FORCEPROP 1 LAST VALUE 10UF
J 0
(-4400 5800);
DISPLAY 0.489362 (-4400 5800);
PAINT SKYBLUE (-4400 5800);
FORCEPROP 1 LAST PART_NUMBER CH6104KEA00
J 0
(-4400 5600);
DISPLAY 0.489362 (-4400 5600);
PAINT SKYBLUE (-4400 5600);
FORCEPROP 1 LAST VOLTAGE 25V
J 0
(-4400 5750);
DISPLAY 0.489362 (-4400 5750);
PAINT SKYBLUE (-4400 5750);
FORCEPROP 1 LAST PACK_TYPE C0805
J 0
(-4400 5550);
DISPLAY 0.489362 (-4400 5550);
PAINT SKYBLUE (-4400 5550);
FORCEPROP 2 LAST CDS_LIB pure_quanta
J 0
(-4450 5750);
DISPLAY INVISIBLE (-4450 5750);
FORCEPROP 1 LAST PATH I25
J 0
(-4400 5900);
DISPLAY 0.978723 (-4400 5900);
PAINT WHITE (-4400 5900);
DISPLAY INVISIBLE (-4400 5900);
FORCEADD Q_CAP..1
(-4150 5750);
FORCEPROP 1 LAST LOCATION PC591_1
J 0
(-4100 5850);
DISPLAY 0.489362 (-4100 5850);
PAINT SKYBLUE (-4100 5850);
FORCEPROP 0 LAST $SEC 1
J 0
(-4100 5875);
DISPLAY 0.680851 (-4100 5875);
PAINT MONO (-4100 5875);
DISPLAY INVISIBLE (-4100 5875);
FORCEPROP 0 LAST CDS_SEC 1
J 0
(-4100 5875);
DISPLAY 1.021277 (-4100 5875);
DISPLAY INVISIBLE (-4100 5875);
FORCEPROP 1 LASTPIN (-4150 5850) $PN 1
J 0
(-4140 5830);
DISPLAY 0.489362 (-4140 5830);
PAINT MONO (-4140 5830);
FORCEPROP 1 LASTPIN (-4150 5650) $PN 2
J 0
(-4140 5630);
DISPLAY 0.489362 (-4140 5630);
PAINT MONO (-4140 5630);
FORCEPROP 1 LAST MATERIAL X6S
J 0
(-4100 5650);
DISPLAY 0.489362 (-4100 5650);
PAINT SKYBLUE (-4100 5650);
FORCEPROP 1 LAST TOLERANCE 10%
J 0
(-4100 5700);
DISPLAY 0.489362 (-4100 5700);
PAINT SKYBLUE (-4100 5700);
FORCEPROP 1 LAST VALUE 10UF
J 0
(-4100 5800);
DISPLAY 0.489362 (-4100 5800);
PAINT SKYBLUE (-4100 5800);
FORCEPROP 1 LAST VOLTAGE 25V
J 0
(-4100 5750);
DISPLAY 0.489362 (-4100 5750);
PAINT SKYBLUE (-4100 5750);
FORCEPROP 1 LAST PACK_TYPE C0805
J 0
(-4100 5550);
DISPLAY 0.489362 (-4100 5550);
PAINT SKYBLUE (-4100 5550);
FORCEPROP 1 LAST PART_NUMBER CH6104KEA00
J 0
(-4100 5600);
DISPLAY 0.489362 (-4100 5600);
PAINT SKYBLUE (-4100 5600);
FORCEPROP 2 LAST CDS_LIB pure_quanta
J 0
(-4150 5750);
DISPLAY INVISIBLE (-4150 5750);
FORCEPROP 1 LAST PATH I26
J 0
(-4100 5900);
DISPLAY 0.978723 (-4100 5900);
PAINT WHITE (-4100 5900);
DISPLAY INVISIBLE (-4100 5900);
FORCEADD Q_CAP..1
(-1700 4725);
FORCEPROP 1 LAST LOCATION PC599
J 0
(-1650 4825);
DISPLAY 0.489362 (-1650 4825);
PAINT SKYBLUE (-1650 4825);
FORCEPROP 0 LAST $SEC 1
J 0
(-1650 4850);
DISPLAY 0.680851 (-1650 4850);
PAINT MONO (-1650 4850);
DISPLAY INVISIBLE (-1650 4850);
FORCEPROP 0 LAST CDS_SEC 1
J 0
(-1650 4850);
DISPLAY 1.021277 (-1650 4850);
DISPLAY INVISIBLE (-1650 4850);
FORCEPROP 1 LASTPIN (-1700 4825) $PN 1
J 0
(-1690 4805);
DISPLAY 0.489362 (-1690 4805);
PAINT MONO (-1690 4805);
FORCEPROP 1 LASTPIN (-1700 4625) $PN 2
J 0
(-1690 4605);
DISPLAY 0.489362 (-1690 4605);
PAINT MONO (-1690 4605);
FORCEPROP 1 LAST MATERIAL X7R
J 0
(-1650 4625);
DISPLAY 0.489362 (-1650 4625);
PAINT SKYBLUE (-1650 4625);
FORCEPROP 1 LAST PART_NUMBER CH4104K1B00
J 0
(-1650 4575);
DISPLAY 0.489362 (-1650 4575);
PAINT SKYBLUE (-1650 4575);
FORCEPROP 1 LAST PACK_TYPE 0402
J 0
(-1650 4525);
DISPLAY 0.489362 (-1650 4525);
PAINT SKYBLUE (-1650 4525);
FORCEPROP 1 LAST VALUE 0.1UF
J 0
(-1650 4775);
DISPLAY 0.489362 (-1650 4775);
PAINT SKYBLUE (-1650 4775);
FORCEPROP 1 LAST VOLTAGE 25V
J 0
(-1650 4725);
DISPLAY 0.489362 (-1650 4725);
PAINT SKYBLUE (-1650 4725);
FORCEPROP 1 LAST TOLERANCE 10%
J 0
(-1650 4675);
DISPLAY 0.489362 (-1650 4675);
PAINT SKYBLUE (-1650 4675);
FORCEPROP 2 LAST CDS_LIB pure_quanta
J 0
(-1700 4725);
DISPLAY INVISIBLE (-1700 4725);
FORCEPROP 1 LAST PATH I29
J 0
(-1650 4875);
DISPLAY 0.978723 (-1650 4875);
PAINT WHITE (-1650 4875);
DISPLAY INVISIBLE (-1650 4875);
FORCEADD OFFPAGE..1
(-8075 4800);
FORCEPROP 2 LAST $XR5 175 
J 0
(-8927 4800);
DISPLAY 0.638298 (-8927 4800);
PAINT MONO (-8927 4800);
FORCEPROP 2 LAST $XR4 174 
J 0
(-8807 4800);
DISPLAY 0.638298 (-8807 4800);
PAINT MONO (-8807 4800);
FORCEPROP 2 LAST $XR3 172 
J 0
(-8687 4800);
DISPLAY 0.638298 (-8687 4800);
PAINT MONO (-8687 4800);
FORCEPROP 2 LAST $XR2 171 
J 0
(-8567 4800);
DISPLAY 0.638298 (-8567 4800);
PAINT MONO (-8567 4800);
FORCEPROP 2 LAST $XR1 170 
J 0
(-8447 4800);
DISPLAY 0.638298 (-8447 4800);
PAINT MONO (-8447 4800);
FORCEPROP 2 LAST $XR0 169 
J 0
(-8327 4800);
DISPLAY 0.638298 (-8327 4800);
PAINT MONO (-8327 4800);
FORCEPROP 2 LAST PATH I3
J 0
(-8025 4875);
DISPLAY 1.021277 (-8025 4875);
DISPLAY INVISIBLE (-8025 4875);
FORCEPROP 1 LAST COMMENT_BODY TRUE
J 0
(-7950 4700);
DISPLAY 0.872340 (-7950 4700);
PAINT GREEN (-7950 4700);
DISPLAY INVISIBLE (-7950 4700);
FORCEPROP 1 LAST OFFPAGE TRUE
J 0
(-7750 4675);
DISPLAY 0.872340 (-7750 4675);
PAINT GREEN (-7750 4675);
DISPLAY INVISIBLE (-7750 4675);
FORCEPROP 2 LAST CDS_LIB standard
J 0
(-8075 4800);
DISPLAY INVISIBLE (-8075 4800);
FORCEADD UNIVERSAL_GND..1
(-3875 5425);
FORCEPROP 3 LASTPIN (-3875 5475) SIG_NAME GND\g
J 0
(-3865 5485);
DISPLAY 0.659574 (-3865 5485);
PAINT MONO (-3865 5485);
DISPLAY INVISIBLE (-3865 5485);
FORCEPROP 2 LAST CDS_LIB pure_quanta_power
J 0
(-3875 5425);
DISPLAY INVISIBLE (-3875 5425);
FORCEPROP 1 LAST PATH I31
J 0
(-3800 5425);
DISPLAY 0.872340 (-3800 5425);
PAINT AQUA (-3800 5425);
DISPLAY INVISIBLE (-3800 5425);
FORCEPROP 1 LAST HDL_POWER GND
J 1
(-3850 5350);
DISPLAY 0.872340 (-3850 5350);
PAINT GREEN (-3850 5350);
DISPLAY INVISIBLE (-3850 5350);
FORCEADD Q_INDUCTOR..1
(-2975 5950);
FORCEPROP 1 LAST LOCATION PL65
J 0
(-3100 6110);
DISPLAY 0.489362 (-3100 6110);
PAINT SKYBLUE (-3100 6110);
FORCEPROP 0 LAST $SEC 1
J 0
(-3100 6225);
DISPLAY 0.680851 (-3100 6225);
PAINT MONO (-3100 6225);
DISPLAY INVISIBLE (-3100 6225);
FORCEPROP 0 LAST CDS_SEC 1
J 0
(-3100 6225);
DISPLAY 1.021277 (-3100 6225);
DISPLAY INVISIBLE (-3100 6225);
FORCEPROP 0 LASTPIN (-3075 5925) $PN 1
J 2
(-3085 5935);
DISPLAY 0.489362 (-3085 5935);
PAINT MONO (-3085 5935);
FORCEPROP 0 LASTPIN (-2875 5925) $PN 2
J 0
(-2865 5935);
DISPLAY 0.489362 (-2865 5935);
PAINT MONO (-2865 5935);
FORCEPROP 1 LAST MATERIAL IND
J 0
(-3100 6005);
DISPLAY 0.489362 (-3100 6005);
PAINT SKYBLUE (-3100 6005);
FORCEPROP 2 LAST VALUE 50NH/86A
J 0
(-3100 6200);
DISPLAY 0.489362 (-3100 6200);
PAINT SKYBLUE (-3100 6200);
FORCEPROP 1 LAST PART_NUMBER CVA50^0MZ09
J 0
(-3100 6060);
DISPLAY 0.489362 (-3100 6060);
PAINT SKYBLUE (-3100 6060);
FORCEPROP 2 LAST PACK_TYPE SMLF
J 0
(-3100 6150);
DISPLAY 0.489362 (-3100 6150);
PAINT SKYBLUE (-3100 6150);
FORCEPROP 2 LAST CDS_LIB pure_quanta
J 0
(-2975 5950);
DISPLAY INVISIBLE (-2975 5950);
FORCEPROP 1 LAST NEEDS_NO_SIZE TRUE
J 0
(-2975 5950);
DISPLAY 0.468085 (-2975 5950);
PAINT GREEN (-2975 5950);
DISPLAY INVISIBLE (-2975 5950);
FORCEPROP 1 LAST PATH I34
J 0
(-2900 6005);
DISPLAY 0.723404 (-2900 6005);
PAINT GREEN (-2900 6005);
DISPLAY INVISIBLE (-2900 6005);
FORCEADD VCC_CORE..1
(-2675 6025);
FORCEPROP 3 LASTPIN (-2675 5975) SIG_NAME P12V_STBY\g
J 0
(-2665 5985);
DISPLAY 0.659574 (-2665 5985);
PAINT MONO (-2665 5985);
DISPLAY INVISIBLE (-2665 5985);
FORCEPROP 1 LAST HDL_POWER P12V_STBY
J 1
(-2675 6075);
DISPLAY 0.489362 (-2675 6075);
PAINT GREEN (-2675 6075);
FORCEPROP 2 LAST CDS_LIB pure_quanta_power
J 0
(-2675 6025);
DISPLAY INVISIBLE (-2675 6025);
FORCEPROP 1 LAST PATH I35
J 0
(-2625 6050);
DISPLAY 0.872340 (-2625 6050);
PAINT AQUA (-2625 6050);
DISPLAY INVISIBLE (-2625 6050);
FORCEADD Q_CAP..1
(-1325 4725);
FORCEPROP 1 LAST LOCATION PC602_1
J 0
(-1275 4825);
DISPLAY 0.489362 (-1275 4825);
PAINT SKYBLUE (-1275 4825);
FORCEPROP 0 LAST $SEC 1
J 0
(-1275 4850);
DISPLAY 0.680851 (-1275 4850);
PAINT MONO (-1275 4850);
DISPLAY INVISIBLE (-1275 4850);
FORCEPROP 0 LAST CDS_SEC 1
J 0
(-1275 4850);
DISPLAY 1.021277 (-1275 4850);
DISPLAY INVISIBLE (-1275 4850);
FORCEPROP 1 LASTPIN (-1325 4825) $PN 1
J 0
(-1315 4805);
DISPLAY 0.489362 (-1315 4805);
PAINT MONO (-1315 4805);
FORCEPROP 1 LASTPIN (-1325 4625) $PN 2
J 0
(-1315 4605);
DISPLAY 0.489362 (-1315 4605);
PAINT MONO (-1315 4605);
FORCEPROP 1 LAST MATERIAL X6S
J 0
(-1275 4625);
DISPLAY 0.489362 (-1275 4625);
PAINT SKYBLUE (-1275 4625);
FORCEPROP 1 LAST TOLERANCE 20%
J 0
(-1275 4675);
DISPLAY 0.489362 (-1275 4675);
PAINT SKYBLUE (-1275 4675);
FORCEPROP 1 LAST VALUE 22UF
J 0
(-1275 4775);
DISPLAY 0.489362 (-1275 4775);
PAINT SKYBLUE (-1275 4775);
FORCEPROP 1 LAST PART_NUMBER TMP_QCH622KMEA01
J 0
(-1275 4575);
DISPLAY 0.489362 (-1275 4575);
PAINT SKYBLUE (-1275 4575);
FORCEPROP 1 LAST VOLTAGE 4V
J 0
(-1275 4725);
DISPLAY 0.489362 (-1275 4725);
PAINT SKYBLUE (-1275 4725);
FORCEPROP 1 LAST PACK_TYPE 0805
J 0
(-1275 4525);
DISPLAY 0.489362 (-1275 4525);
PAINT SKYBLUE (-1275 4525);
FORCEPROP 2 LAST CDS_LIB pure_quanta
J 0
(-1325 4725);
DISPLAY INVISIBLE (-1325 4725);
FORCEPROP 1 LAST PATH I37
J 0
(-1275 4875);
DISPLAY 0.978723 (-1275 4875);
PAINT WHITE (-1275 4875);
DISPLAY INVISIBLE (-1275 4875);
FORCEADD UNIVERSAL_GND..1
(-550 4300);
FORCEPROP 3 LASTPIN (-550 4350) SIG_NAME GND\g
J 0
(-540 4360);
DISPLAY 0.659574 (-540 4360);
PAINT MONO (-540 4360);
DISPLAY INVISIBLE (-540 4360);
FORCEPROP 2 LAST CDS_LIB pure_quanta_power
J 0
(-550 4300);
DISPLAY INVISIBLE (-550 4300);
FORCEPROP 1 LAST PATH I38
J 0
(-475 4300);
DISPLAY 0.872340 (-475 4300);
PAINT AQUA (-475 4300);
DISPLAY INVISIBLE (-475 4300);
FORCEPROP 1 LAST HDL_POWER GND
J 1
(-525 4225);
DISPLAY 0.872340 (-525 4225);
PAINT GREEN (-525 4225);
DISPLAY INVISIBLE (-525 4225);
FORCEADD Q_CAP..1
(-875 4725);
FORCEPROP 1 LAST LOCATION PC604_1
J 0
(-825 4825);
DISPLAY 0.489362 (-825 4825);
PAINT SKYBLUE (-825 4825);
FORCEPROP 0 LAST $SEC 1
J 0
(-825 4850);
DISPLAY 0.680851 (-825 4850);
PAINT MONO (-825 4850);
DISPLAY INVISIBLE (-825 4850);
FORCEPROP 0 LAST CDS_SEC 1
J 0
(-825 4850);
DISPLAY 1.021277 (-825 4850);
DISPLAY INVISIBLE (-825 4850);
FORCEPROP 1 LASTPIN (-875 4825) $PN 1
J 0
(-865 4805);
DISPLAY 0.489362 (-865 4805);
PAINT MONO (-865 4805);
FORCEPROP 1 LASTPIN (-875 4625) $PN 2
J 0
(-865 4605);
DISPLAY 0.489362 (-865 4605);
PAINT MONO (-865 4605);
FORCEPROP 1 LAST MATERIAL X6S
J 0
(-825 4625);
DISPLAY 0.489362 (-825 4625);
PAINT SKYBLUE (-825 4625);
FORCEPROP 1 LAST TOLERANCE 20%
J 0
(-825 4675);
DISPLAY 0.489362 (-825 4675);
PAINT SKYBLUE (-825 4675);
FORCEPROP 1 LAST VALUE 22UF
J 0
(-825 4775);
DISPLAY 0.489362 (-825 4775);
PAINT SKYBLUE (-825 4775);
FORCEPROP 1 LAST VOLTAGE 4V
J 0
(-825 4725);
DISPLAY 0.489362 (-825 4725);
PAINT SKYBLUE (-825 4725);
FORCEPROP 1 LAST PACK_TYPE 0805
J 0
(-825 4575);
DISPLAY 0.489362 (-825 4575);
PAINT SKYBLUE (-825 4575);
FORCEPROP 2 LAST CDS_LIB pure_quanta
J 0
(-875 4725);
DISPLAY INVISIBLE (-875 4725);
FORCEPROP 1 LAST PATH I39
J 0
(-825 4875);
DISPLAY 0.978723 (-825 4875);
PAINT WHITE (-825 4875);
DISPLAY INVISIBLE (-825 4875);
FORCEPROP 1 LAST PART_NUMBER TMP_QCH622KMEA01
J 0
(-825 4575);
DISPLAY 0.489362 (-825 4575);
PAINT SKYBLUE (-825 4575);
DISPLAY INVISIBLE (-825 4575);
FORCEADD Q_CAP..1
(-7850 4625);
FORCEPROP 1 LAST LOCATION PC577_7
J 0
(-7800 4725);
DISPLAY 0.489362 (-7800 4725);
PAINT SKYBLUE (-7800 4725);
FORCEPROP 0 LAST $SEC 1
J 0
(-7800 4750);
DISPLAY 0.680851 (-7800 4750);
PAINT MONO (-7800 4750);
DISPLAY INVISIBLE (-7800 4750);
FORCEPROP 0 LAST CDS_SEC 1
J 0
(-7800 4750);
DISPLAY 1.021277 (-7800 4750);
DISPLAY INVISIBLE (-7800 4750);
FORCEPROP 1 LASTPIN (-7850 4725) $PN 1
J 0
(-7840 4705);
DISPLAY 0.489362 (-7840 4705);
PAINT MONO (-7840 4705);
FORCEPROP 1 LASTPIN (-7850 4525) $PN 2
J 0
(-7840 4505);
DISPLAY 0.489362 (-7840 4505);
PAINT MONO (-7840 4505);
FORCEPROP 1 LAST MATERIAL X7R
J 0
(-7800 4525);
DISPLAY 0.489362 (-7800 4525);
PAINT SKYBLUE (-7800 4525);
FORCEPROP 1 LAST TOLERANCE 10%
J 0
(-7800 4575);
DISPLAY 0.489362 (-7800 4575);
PAINT SKYBLUE (-7800 4575);
FORCEPROP 1 LAST VALUE 0.1UF
J 0
(-7800 4675);
DISPLAY 0.489362 (-7800 4675);
PAINT SKYBLUE (-7800 4675);
FORCEPROP 1 LAST PART_NUMBER CH4104K1B00
J 0
(-7800 4475);
DISPLAY 0.489362 (-7800 4475);
PAINT SKYBLUE (-7800 4475);
FORCEPROP 1 LAST VOLTAGE 25V
J 0
(-7800 4625);
DISPLAY 0.489362 (-7800 4625);
PAINT SKYBLUE (-7800 4625);
FORCEPROP 1 LAST PACK_TYPE 0402
J 0
(-7800 4425);
DISPLAY 0.489362 (-7800 4425);
PAINT SKYBLUE (-7800 4425);
FORCEPROP 2 LAST CDS_LIB pure_quanta
J 0
(-7850 4625);
DISPLAY INVISIBLE (-7850 4625);
FORCEPROP 1 LAST PATH I4
J 0
(-7800 4775);
DISPLAY 0.978723 (-7800 4775);
PAINT WHITE (-7800 4775);
DISPLAY INVISIBLE (-7800 4775);
FORCEADD VCC_CORE..1
(-550 5025);
FORCEPROP 3 LASTPIN (-550 4975) SIG_NAME PVDDCR_SOC_P0\g
J 0
(-540 4985);
DISPLAY 0.659574 (-540 4985);
PAINT MONO (-540 4985);
DISPLAY INVISIBLE (-540 4985);
FORCEPROP 1 LAST HDL_POWER PVDDCR_SOC_P0
J 1
(-550 5075);
DISPLAY 0.489362 (-550 5075);
PAINT GREEN (-550 5075);
FORCEPROP 2 LAST CDS_LIB pure_quanta_power
J 0
(-550 5025);
DISPLAY INVISIBLE (-550 5025);
FORCEPROP 1 LAST PATH I40
J 0
(-500 5050);
DISPLAY 0.872340 (-500 5050);
PAINT AQUA (-500 5050);
DISPLAY INVISIBLE (-500 5050);
FORCEADD Q_INDUCTOR4P_14..1
(-3100 4775);
FORCEPROP 1 LAST LOCATION PL63
J 0
(-3325 5030);
DISPLAY 0.489362 (-3325 5030);
PAINT SKYBLUE (-3325 5030);
FORCEPROP 0 LAST $SEC 1
J 0
(-3325 5175);
DISPLAY 0.680851 (-3325 5175);
PAINT MONO (-3325 5175);
DISPLAY INVISIBLE (-3325 5175);
FORCEPROP 0 LAST CDS_SEC 1
J 0
(-3325 5175);
DISPLAY 1.021277 (-3325 5175);
DISPLAY INVISIBLE (-3325 5175);
FORCEPROP 0 LASTPIN (-3500 4900) $PN 1
J 2
(-3510 4910);
DISPLAY 0.489362 (-3510 4910);
PAINT MONO (-3510 4910);
FORCEPROP 0 LASTPIN (-3500 4650) $PN 2
J 2
(-3510 4660);
DISPLAY 0.489362 (-3510 4660);
PAINT MONO (-3510 4660);
FORCEPROP 0 LASTPIN (-2700 4650) $PN 3
J 0
(-2690 4660);
DISPLAY 0.489362 (-2690 4660);
PAINT MONO (-2690 4660);
FORCEPROP 0 LASTPIN (-2700 4900) $PN 4
J 0
(-2690 4910);
DISPLAY 0.489362 (-2690 4910);
PAINT MONO (-2690 4910);
FORCEPROP 1 LAST PART_NUMBER CV+15^0TZ04
J 0
(-3325 4935);
DISPLAY 0.489362 (-3325 4935);
PAINT SKYBLUE (-3325 4935);
FORCEPROP 2 LAST PART_TYPE SMLF
J 0
(-3325 5125);
DISPLAY 1.021277 (-3325 5125);
FORCEPROP 1 LAST MATERIAL IND
J 0
(-3325 4985);
DISPLAY 0.489362 (-3325 4985);
PAINT SKYBLUE (-3325 4985);
FORCEPROP 2 LAST VALUE 150NH
J 0
(-3325 5075);
DISPLAY 0.489362 (-3325 5075);
PAINT SKYBLUE (-3325 5075);
FORCEPROP 2 LAST CDS_LIB pure_quanta
J 0
(-3100 4775);
DISPLAY INVISIBLE (-3100 4775);
FORCEPROP 1 LAST NEEDS_NO_SIZE TRUE
J 0
(-3100 4775);
DISPLAY 0.468085 (-3100 4775);
PAINT GREEN (-3100 4775);
DISPLAY INVISIBLE (-3100 4775);
FORCEPROP 1 LAST PATH I42
J 0
(-2900 4930);
DISPLAY 0.723404 (-2900 4930);
PAINT GREEN (-2900 4930);
DISPLAY INVISIBLE (-2900 4930);
FORCEADD Q_CAP..1
(-3875 5125);
FORCEPROP 1 LAST LOCATION PC593
J 0
(-3825 5250);
DISPLAY 0.489362 (-3825 5250);
PAINT SKYBLUE (-3825 5250);
FORCEPROP 0 LAST $SEC 1
J 0
(-3825 5275);
DISPLAY 0.680851 (-3825 5275);
PAINT MONO (-3825 5275);
DISPLAY INVISIBLE (-3825 5275);
FORCEPROP 0 LAST CDS_SEC 1
J 0
(-3825 5275);
DISPLAY 1.021277 (-3825 5275);
DISPLAY INVISIBLE (-3825 5275);
FORCEPROP 1 LASTPIN (-3875 5225) $PN 1
J 0
(-3865 5205);
DISPLAY 0.489362 (-3865 5205);
PAINT MONO (-3865 5205);
FORCEPROP 1 LASTPIN (-3875 5025) $PN 2
J 0
(-3865 5005);
DISPLAY 0.489362 (-3865 5005);
PAINT MONO (-3865 5005);
FORCEPROP 1 LAST VALUE 0.22UF
J 0
(-3825 5200);
DISPLAY 0.489362 (-3825 5200);
PAINT SKYBLUE (-3825 5200);
FORCEPROP 1 LAST VOLTAGE 16V
J 0
(-3825 5150);
DISPLAY 0.489362 (-3825 5150);
PAINT SKYBLUE (-3825 5150);
FORCEPROP 1 LAST MATERIAL X7R
J 0
(-3825 5050);
DISPLAY 0.489362 (-3825 5050);
PAINT SKYBLUE (-3825 5050);
FORCEPROP 1 LAST TOLERANCE 10%
J 0
(-3825 5100);
DISPLAY 0.489362 (-3825 5100);
PAINT SKYBLUE (-3825 5100);
FORCEPROP 1 LAST PART_NUMBER CH4223K1B00
J 0
(-3825 5000);
DISPLAY 0.489362 (-3825 5000);
PAINT SKYBLUE (-3825 5000);
FORCEPROP 1 LAST PACK_TYPE 0402
J 0
(-3825 4950);
DISPLAY 0.489362 (-3825 4950);
PAINT SKYBLUE (-3825 4950);
FORCEPROP 2 LAST CDS_LIB pure_quanta
J 0
(-3875 5125);
DISPLAY INVISIBLE (-3875 5125);
FORCEPROP 1 LAST PATH I43
J 0
(-3825 5275);
DISPLAY 0.978723 (-3825 5275);
PAINT WHITE (-3825 5275);
DISPLAY INVISIBLE (-3825 5275);
FORCEADD OFFPAGE..1
(-8050 1700);
FORCEPROP 2 LAST $XR5 175 
J 0
(-8932 1700);
DISPLAY 0.638298 (-8932 1700);
PAINT MONO (-8932 1700);
FORCEPROP 2 LAST $XR4 174 
J 0
(-8812 1700);
DISPLAY 0.638298 (-8812 1700);
PAINT MONO (-8812 1700);
FORCEPROP 2 LAST $XR3 172 
J 0
(-8692 1700);
DISPLAY 0.638298 (-8692 1700);
PAINT MONO (-8692 1700);
FORCEPROP 2 LAST $XR2 171 
J 0
(-8572 1700);
DISPLAY 0.638298 (-8572 1700);
PAINT MONO (-8572 1700);
FORCEPROP 2 LAST $XR1 170 
J 0
(-8452 1700);
DISPLAY 0.638298 (-8452 1700);
PAINT MONO (-8452 1700);
FORCEPROP 2 LAST $XR0 169 
J 0
(-8332 1700);
DISPLAY 0.638298 (-8332 1700);
PAINT MONO (-8332 1700);
FORCEPROP 2 LAST PATH I45
J 0
(-8000 1775);
DISPLAY 1.021277 (-8000 1775);
DISPLAY INVISIBLE (-8000 1775);
FORCEPROP 1 LAST COMMENT_BODY TRUE
J 0
(-7925 1600);
DISPLAY 0.872340 (-7925 1600);
PAINT GREEN (-7925 1600);
DISPLAY INVISIBLE (-7925 1600);
FORCEPROP 1 LAST OFFPAGE TRUE
J 0
(-7725 1575);
DISPLAY 0.872340 (-7725 1575);
PAINT GREEN (-7725 1575);
DISPLAY INVISIBLE (-7725 1575);
FORCEPROP 2 LAST CDS_LIB standard
J 0
(-8050 1700);
DISPLAY INVISIBLE (-8050 1700);
FORCEADD UNIVERSAL_GND..1
(-5425 1100);
FORCEPROP 3 LASTPIN (-5425 1150) SIG_NAME GND\g
J 0
(-5415 1160);
DISPLAY 0.659574 (-5415 1160);
PAINT MONO (-5415 1160);
DISPLAY INVISIBLE (-5415 1160);
FORCEPROP 2 LAST CDS_LIB pure_quanta_power
J 0
(-5425 1100);
DISPLAY INVISIBLE (-5425 1100);
FORCEPROP 1 LAST PATH I46
J 0
(-5350 1100);
DISPLAY 0.872340 (-5350 1100);
PAINT AQUA (-5350 1100);
DISPLAY INVISIBLE (-5350 1100);
FORCEPROP 1 LAST HDL_POWER GND
J 1
(-5400 1025);
DISPLAY 0.872340 (-5400 1025);
PAINT GREEN (-5400 1025);
DISPLAY INVISIBLE (-5400 1025);
FORCEADD OFFPAGE..1
(-7100 1200);
FORCEPROP 2 LAST $XR0 169 
J 0
(-7352 1200);
DISPLAY 0.638298 (-7352 1200);
PAINT MONO (-7352 1200);
FORCEPROP 2 LAST PATH I47
J 0
(-7050 1275);
DISPLAY 1.021277 (-7050 1275);
DISPLAY INVISIBLE (-7050 1275);
FORCEPROP 1 LAST COMMENT_BODY TRUE
J 0
(-6975 1100);
DISPLAY 0.872340 (-6975 1100);
PAINT GREEN (-6975 1100);
DISPLAY INVISIBLE (-6975 1100);
FORCEPROP 1 LAST OFFPAGE TRUE
J 0
(-6775 1075);
DISPLAY 0.872340 (-6775 1075);
PAINT GREEN (-6775 1075);
DISPLAY INVISIBLE (-6775 1075);
FORCEPROP 2 LAST CDS_LIB standard
J 2
(-7100 1200);
DISPLAY INVISIBLE (-7100 1200);
FORCEADD Q_CAP..1
(-7825 1525);
FORCEPROP 1 LAST LOCATION PC578_8
J 0
(-7775 1625);
DISPLAY 0.489362 (-7775 1625);
PAINT SKYBLUE (-7775 1625);
FORCEPROP 0 LAST $SEC 1
J 0
(-7775 1650);
DISPLAY 0.680851 (-7775 1650);
PAINT MONO (-7775 1650);
DISPLAY INVISIBLE (-7775 1650);
FORCEPROP 0 LAST CDS_SEC 1
J 0
(-7775 1650);
DISPLAY 1.021277 (-7775 1650);
DISPLAY INVISIBLE (-7775 1650);
FORCEPROP 1 LASTPIN (-7825 1625) $PN 1
J 0
(-7815 1605);
DISPLAY 0.489362 (-7815 1605);
PAINT MONO (-7815 1605);
FORCEPROP 1 LASTPIN (-7825 1425) $PN 2
J 0
(-7815 1405);
DISPLAY 0.489362 (-7815 1405);
PAINT MONO (-7815 1405);
FORCEPROP 1 LAST PACK_TYPE 0402
J 0
(-7775 1325);
DISPLAY 0.489362 (-7775 1325);
PAINT SKYBLUE (-7775 1325);
FORCEPROP 1 LAST VOLTAGE 25V
J 0
(-7775 1525);
DISPLAY 0.489362 (-7775 1525);
PAINT SKYBLUE (-7775 1525);
FORCEPROP 1 LAST PART_NUMBER CH4104K1B00
J 0
(-7775 1375);
DISPLAY 0.489362 (-7775 1375);
PAINT SKYBLUE (-7775 1375);
FORCEPROP 1 LAST TOLERANCE 10%
J 0
(-7775 1475);
DISPLAY 0.489362 (-7775 1475);
PAINT SKYBLUE (-7775 1475);
FORCEPROP 1 LAST MATERIAL X7R
J 0
(-7775 1425);
DISPLAY 0.489362 (-7775 1425);
PAINT SKYBLUE (-7775 1425);
FORCEPROP 1 LAST VALUE 0.1UF
J 0
(-7775 1575);
DISPLAY 0.489362 (-7775 1575);
PAINT SKYBLUE (-7775 1575);
FORCEPROP 1 LAST PATH I48
J 0
(-7775 1675);
DISPLAY 0.978723 (-7775 1675);
PAINT WHITE (-7775 1675);
DISPLAY INVISIBLE (-7775 1675);
FORCEPROP 2 LAST CDS_LIB pure_quanta
J 0
(-7825 1525);
DISPLAY INVISIBLE (-7825 1525);
FORCEADD UNIVERSAL_GND..1
(-7825 1250);
FORCEPROP 3 LASTPIN (-7825 1300) SIG_NAME GND\g
J 0
(-7815 1310);
DISPLAY 0.659574 (-7815 1310);
PAINT MONO (-7815 1310);
DISPLAY INVISIBLE (-7815 1310);
FORCEPROP 2 LAST CDS_LIB pure_quanta_power
J 0
(-7825 1250);
DISPLAY INVISIBLE (-7825 1250);
FORCEPROP 1 LAST PATH I49
J 0
(-7750 1250);
DISPLAY 0.872340 (-7750 1250);
PAINT AQUA (-7750 1250);
DISPLAY INVISIBLE (-7750 1250);
FORCEPROP 1 LAST HDL_POWER GND
J 1
(-7800 1175);
DISPLAY 0.872340 (-7800 1175);
PAINT GREEN (-7800 1175);
DISPLAY INVISIBLE (-7800 1175);
FORCEADD UNIVERSAL_GND..1
(-7850 4350);
FORCEPROP 3 LASTPIN (-7850 4400) SIG_NAME GND\g
J 0
(-7840 4410);
DISPLAY 0.659574 (-7840 4410);
PAINT MONO (-7840 4410);
DISPLAY INVISIBLE (-7840 4410);
FORCEPROP 2 LAST CDS_LIB pure_quanta_power
J 0
(-7850 4350);
DISPLAY INVISIBLE (-7850 4350);
FORCEPROP 1 LAST PATH I5
J 0
(-7775 4350);
DISPLAY 0.872340 (-7775 4350);
PAINT AQUA (-7775 4350);
DISPLAY INVISIBLE (-7775 4350);
FORCEPROP 1 LAST HDL_POWER GND
J 1
(-7825 4275);
DISPLAY 0.872340 (-7825 4275);
PAINT GREEN (-7825 4275);
DISPLAY INVISIBLE (-7825 4275);
FORCEADD UNIVERSAL_GND..1
(-7500 1325);
FORCEPROP 3 LASTPIN (-7500 1375) SIG_NAME GND\g
J 0
(-7490 1385);
DISPLAY 0.659574 (-7490 1385);
PAINT MONO (-7490 1385);
DISPLAY INVISIBLE (-7490 1385);
FORCEPROP 2 LAST CDS_LIB pure_quanta_power
J 0
(-7500 1325);
DISPLAY INVISIBLE (-7500 1325);
FORCEPROP 1 LAST PATH I50
J 0
(-7425 1325);
DISPLAY 0.872340 (-7425 1325);
PAINT AQUA (-7425 1325);
DISPLAY INVISIBLE (-7425 1325);
FORCEPROP 1 LAST HDL_POWER GND
J 1
(-7475 1250);
DISPLAY 0.872340 (-7475 1250);
PAINT GREEN (-7475 1250);
DISPLAY INVISIBLE (-7475 1250);
FORCEADD OFFPAGE..2
R 2
(-7125 1300);
FORCEPROP 2 LAST $XR2 169 
J 0
(-7500 1264);
DISPLAY 0.638298 (-7500 1264);
PAINT MONO (-7500 1264);
FORCEPROP 2 LAST $XR1 175 
J 0
(-7380 1264);
DISPLAY 0.638298 (-7380 1264);
PAINT MONO (-7380 1264);
FORCEPROP 2 LAST $XR0 174 
J 0
(-7380 1300);
DISPLAY 0.638298 (-7380 1300);
PAINT MONO (-7380 1300);
FORCEPROP 2 LAST PATH I51
J 0
(-7075 1375);
DISPLAY 1.021277 (-7075 1375);
DISPLAY INVISIBLE (-7075 1375);
FORCEPROP 1 LAST COMMENT_BODY TRUE
J 2
(-7080 1205);
DISPLAY 0.872340 (-7080 1205);
PAINT GREEN (-7080 1205);
DISPLAY INVISIBLE (-7080 1205);
FORCEPROP 1 LAST OFFPAGE TRUE
J 2
(-7450 1175);
DISPLAY 0.872340 (-7450 1175);
PAINT GREEN (-7450 1175);
DISPLAY INVISIBLE (-7450 1175);
FORCEPROP 2 LAST CDS_LIB standard
J 0
(-7125 1300);
DISPLAY INVISIBLE (-7125 1300);
FORCEADD Q_RES..1
(-7150 1500);
FORCEPROP 1 LAST LOCATION PR359
J 0
(-7150 1550);
DISPLAY 0.489362 (-7150 1550);
PAINT SKYBLUE (-7150 1550);
FORCEPROP 0 LAST $SEC 1
J 0
(-7150 1575);
DISPLAY 0.680851 (-7150 1575);
PAINT MONO (-7150 1575);
DISPLAY INVISIBLE (-7150 1575);
FORCEPROP 0 LAST CDS_SEC 1
J 0
(-7150 1575);
DISPLAY 1.021277 (-7150 1575);
DISPLAY INVISIBLE (-7150 1575);
FORCEPROP 1 LASTPIN (-7250 1500) $PN 1
J 0
(-7238 1512);
DISPLAY 0.489362 (-7238 1512);
PAINT MONO (-7238 1512);
FORCEPROP 1 LASTPIN (-7050 1500) $PN 2
J 0
(-7088 1512);
DISPLAY 0.489362 (-7088 1512);
PAINT MONO (-7088 1512);
FORCEPROP 1 LAST WATTAGE 1/16W
J 0
(-7050 1400);
DISPLAY 0.489362 (-7050 1400);
PAINT SKYBLUE (-7050 1400);
FORCEPROP 1 LAST MATERIAL EMPTY
J 0
(-7450 1400);
DISPLAY 0.489362 (-7450 1400);
PAINT RED (-7450 1400);
FORCEPROP 1 LAST PART_NUMBER CS28872FB01
J 0
(-7450 1450);
DISPLAY 0.489362 (-7450 1450);
PAINT SKYBLUE (-7450 1450);
FORCEPROP 1 LAST PACK_TYPE 0402LF
J 0
(-7050 1450);
DISPLAY 0.489362 (-7050 1450);
PAINT SKYBLUE (-7050 1450);
FORCEPROP 1 LAST VALUE 8.87K
J 2
(-7275 1525);
DISPLAY 0.489362 (-7275 1525);
PAINT SKYBLUE (-7275 1525);
FORCEPROP 1 LAST TOLERANCE 1%
J 0
(-7025 1525);
DISPLAY 0.489362 (-7025 1525);
PAINT SKYBLUE (-7025 1525);
FORCEPROP 2 LAST CDS_LIB pure_quanta
J 0
(-7150 1500);
DISPLAY INVISIBLE (-7150 1500);
FORCEPROP 1 LAST PATH I52
J 0
(-7200 1650);
DISPLAY 0.978723 (-7200 1650);
PAINT WHITE (-7200 1650);
DISPLAY INVISIBLE (-7200 1650);
FORCEADD OFFPAGE..2
R 2
(-7150 1800);
FORCEPROP 2 LAST $XR0 169 
J 0
(-7405 1800);
DISPLAY 0.638298 (-7405 1800);
PAINT MONO (-7405 1800);
FORCEPROP 2 LAST PATH I55
J 0
(-7100 1875);
DISPLAY 1.021277 (-7100 1875);
DISPLAY INVISIBLE (-7100 1875);
FORCEPROP 1 LAST COMMENT_BODY TRUE
J 2
(-7105 1705);
DISPLAY 0.872340 (-7105 1705);
PAINT GREEN (-7105 1705);
DISPLAY INVISIBLE (-7105 1705);
FORCEPROP 1 LAST OFFPAGE TRUE
J 2
(-7475 1675);
DISPLAY 0.872340 (-7475 1675);
PAINT GREEN (-7475 1675);
DISPLAY INVISIBLE (-7475 1675);
FORCEPROP 2 LAST CDS_LIB standard
J 2
(-7150 1800);
DISPLAY INVISIBLE (-7150 1800);
FORCEADD UNIVERSAL_GND..1
(-7525 4425);
FORCEPROP 3 LASTPIN (-7525 4475) SIG_NAME GND\g
J 0
(-7515 4485);
DISPLAY 0.659574 (-7515 4485);
PAINT MONO (-7515 4485);
DISPLAY INVISIBLE (-7515 4485);
FORCEPROP 2 LAST CDS_LIB pure_quanta_power
J 0
(-7525 4425);
DISPLAY INVISIBLE (-7525 4425);
FORCEPROP 1 LAST PATH I6
J 0
(-7450 4425);
DISPLAY 0.872340 (-7450 4425);
PAINT AQUA (-7450 4425);
DISPLAY INVISIBLE (-7450 4425);
FORCEPROP 1 LAST HDL_POWER GND
J 1
(-7500 4350);
DISPLAY 0.872340 (-7500 4350);
PAINT GREEN (-7500 4350);
DISPLAY INVISIBLE (-7500 4350);
FORCEADD Q_RES..1
(-4675 2150);
FORCEPROP 1 LAST LOCATION PR361
J 0
(-4700 2200);
DISPLAY 0.489362 (-4700 2200);
PAINT SKYBLUE (-4700 2200);
FORCEPROP 0 LAST $SEC 1
J 0
(-4650 2225);
DISPLAY 0.680851 (-4650 2225);
PAINT MONO (-4650 2225);
DISPLAY INVISIBLE (-4650 2225);
FORCEPROP 0 LAST CDS_SEC 1
J 0
(-4650 2225);
DISPLAY 1.021277 (-4650 2225);
DISPLAY INVISIBLE (-4650 2225);
FORCEPROP 1 LASTPIN (-4775 2150) $PN 1
J 0
(-4763 2162);
DISPLAY 0.489362 (-4763 2162);
PAINT MONO (-4763 2162);
FORCEPROP 1 LASTPIN (-4575 2150) $PN 2
J 0
(-4613 2162);
DISPLAY 0.489362 (-4613 2162);
PAINT MONO (-4613 2162);
FORCEPROP 1 LAST PACK_TYPE 0402LF
J 0
(-4575 2050);
DISPLAY 0.489362 (-4575 2050);
PAINT SKYBLUE (-4575 2050);
FORCEPROP 1 LAST TOLERANCE 1%
J 0
(-4550 2175);
DISPLAY 0.489362 (-4550 2175);
PAINT SKYBLUE (-4550 2175);
FORCEPROP 1 LAST MATERIAL CHIP
J 0
(-4925 2050);
DISPLAY 0.489362 (-4925 2050);
PAINT SKYBLUE (-4925 2050);
FORCEPROP 1 LAST WATTAGE 1/16W
J 0
(-4575 2100);
DISPLAY 0.489362 (-4575 2100);
PAINT SKYBLUE (-4575 2100);
FORCEPROP 1 LAST VALUE 4.7
J 2
(-4800 2175);
DISPLAY 0.489362 (-4800 2175);
PAINT SKYBLUE (-4800 2175);
FORCEPROP 1 LAST PART_NUMBER CS-4702FB19
J 0
(-4925 2100);
DISPLAY 0.489362 (-4925 2100);
PAINT SKYBLUE (-4925 2100);
FORCEPROP 1 LAST PATH I63
J 0
(-4725 2300);
DISPLAY 0.978723 (-4725 2300);
PAINT WHITE (-4725 2300);
DISPLAY INVISIBLE (-4725 2300);
FORCEPROP 2 LAST CDS_LIB pure_quanta
J 0
(-4675 2150);
DISPLAY INVISIBLE (-4675 2150);
FORCEADD Q_RES..1
(-4225 800);
FORCEPROP 1 LAST LOCATION PR363
J 0
(-4250 850);
DISPLAY 0.489362 (-4250 850);
PAINT SKYBLUE (-4250 850);
FORCEPROP 0 LAST $SEC 1
J 0
(-4225 875);
DISPLAY 0.680851 (-4225 875);
PAINT MONO (-4225 875);
DISPLAY INVISIBLE (-4225 875);
FORCEPROP 0 LAST CDS_SEC 1
J 0
(-4225 875);
DISPLAY 1.021277 (-4225 875);
DISPLAY INVISIBLE (-4225 875);
FORCEPROP 1 LASTPIN (-4325 800) $PN 1
J 0
(-4313 812);
DISPLAY 0.489362 (-4313 812);
PAINT MONO (-4313 812);
FORCEPROP 1 LASTPIN (-4125 800) $PN 2
J 0
(-4163 812);
DISPLAY 0.489362 (-4163 812);
PAINT MONO (-4163 812);
FORCEPROP 1 LAST WATTAGE 1/16W
J 0
(-4125 750);
DISPLAY 0.489362 (-4125 750);
PAINT SKYBLUE (-4125 750);
FORCEPROP 1 LAST TOLERANCE 5%
J 0
(-4100 825);
DISPLAY 0.489362 (-4100 825);
PAINT SKYBLUE (-4100 825);
FORCEPROP 1 LAST MATERIAL CHIP
J 0
(-4475 700);
DISPLAY 0.489362 (-4475 700);
PAINT SKYBLUE (-4475 700);
FORCEPROP 1 LAST VALUE 0
J 2
(-4350 825);
DISPLAY 0.489362 (-4350 825);
PAINT SKYBLUE (-4350 825);
FORCEPROP 1 LAST PART_NUMBER CS00002JB38
J 0
(-4475 750);
DISPLAY 0.489362 (-4475 750);
PAINT SKYBLUE (-4475 750);
FORCEPROP 1 LAST PACK_TYPE 0402LF
J 0
(-4125 700);
DISPLAY 0.489362 (-4125 700);
PAINT SKYBLUE (-4125 700);
FORCEPROP 2 LAST CDS_LIB pure_quanta
J 0
(-4225 800);
DISPLAY INVISIBLE (-4225 800);
FORCEPROP 1 LAST PATH I65
J 0
(-4275 950);
DISPLAY 0.978723 (-4275 950);
PAINT WHITE (-4275 950);
DISPLAY INVISIBLE (-4275 950);
FORCEADD Q_CAP..1
(-3775 2025);
FORCEPROP 1 LAST LOCATION PC594
J 0
(-3725 2150);
DISPLAY 0.489362 (-3725 2150);
PAINT SKYBLUE (-3725 2150);
FORCEPROP 0 LAST $SEC 1
J 0
(-3725 2175);
DISPLAY 0.680851 (-3725 2175);
PAINT MONO (-3725 2175);
DISPLAY INVISIBLE (-3725 2175);
FORCEPROP 0 LAST CDS_SEC 1
J 0
(-3725 2175);
DISPLAY 1.021277 (-3725 2175);
DISPLAY INVISIBLE (-3725 2175);
FORCEPROP 1 LASTPIN (-3775 2125) $PN 1
J 0
(-3765 2105);
DISPLAY 0.489362 (-3765 2105);
PAINT MONO (-3765 2105);
FORCEPROP 1 LASTPIN (-3775 1925) $PN 2
J 0
(-3765 1905);
DISPLAY 0.489362 (-3765 1905);
PAINT MONO (-3765 1905);
FORCEPROP 1 LAST PACK_TYPE 0402
J 0
(-3725 1850);
DISPLAY 0.489362 (-3725 1850);
PAINT SKYBLUE (-3725 1850);
FORCEPROP 1 LAST PART_NUMBER CH4223K1B00
J 0
(-3725 1900);
DISPLAY 0.489362 (-3725 1900);
PAINT SKYBLUE (-3725 1900);
FORCEPROP 1 LAST MATERIAL X7R
J 0
(-3725 1950);
DISPLAY 0.489362 (-3725 1950);
PAINT SKYBLUE (-3725 1950);
FORCEPROP 1 LAST TOLERANCE 10%
J 0
(-3725 2000);
DISPLAY 0.489362 (-3725 2000);
PAINT SKYBLUE (-3725 2000);
FORCEPROP 1 LAST VALUE 0.22UF
J 0
(-3725 2100);
DISPLAY 0.489362 (-3725 2100);
PAINT SKYBLUE (-3725 2100);
FORCEPROP 1 LAST VOLTAGE 16V
J 0
(-3725 2050);
DISPLAY 0.489362 (-3725 2050);
PAINT SKYBLUE (-3725 2050);
FORCEPROP 2 LAST CDS_LIB pure_quanta
J 0
(-3775 2025);
DISPLAY INVISIBLE (-3775 2025);
FORCEPROP 1 LAST PATH I66
J 0
(-3725 2175);
DISPLAY 0.978723 (-3725 2175);
PAINT WHITE (-3725 2175);
DISPLAY INVISIBLE (-3725 2175);
FORCEADD Q_CAP..1
(-4975 2700);
FORCEPROP 1 LAST LOCATION PC586_2
J 0
(-4925 2800);
DISPLAY 0.489362 (-4925 2800);
PAINT SKYBLUE (-4925 2800);
FORCEPROP 0 LAST $SEC 1
J 0
(-4925 2825);
DISPLAY 0.680851 (-4925 2825);
PAINT MONO (-4925 2825);
DISPLAY INVISIBLE (-4925 2825);
FORCEPROP 0 LAST CDS_SEC 1
J 0
(-4925 2825);
DISPLAY 1.021277 (-4925 2825);
DISPLAY INVISIBLE (-4925 2825);
FORCEPROP 1 LASTPIN (-4975 2800) $PN 1
J 0
(-4965 2780);
DISPLAY 0.489362 (-4965 2780);
PAINT MONO (-4965 2780);
FORCEPROP 1 LASTPIN (-4975 2600) $PN 2
J 0
(-4965 2580);
DISPLAY 0.489362 (-4965 2580);
PAINT MONO (-4965 2580);
FORCEPROP 1 LAST MATERIAL X6S
J 0
(-4925 2600);
DISPLAY 0.489362 (-4925 2600);
PAINT SKYBLUE (-4925 2600);
FORCEPROP 1 LAST TOLERANCE 10%
J 0
(-4925 2650);
DISPLAY 0.489362 (-4925 2650);
PAINT SKYBLUE (-4925 2650);
FORCEPROP 1 LAST VALUE 1UF
J 0
(-4925 2750);
DISPLAY 0.489362 (-4925 2750);
PAINT SKYBLUE (-4925 2750);
FORCEPROP 1 LAST PART_NUMBER CH5104KEB02
J 0
(-4925 2550);
DISPLAY 0.489362 (-4925 2550);
PAINT SKYBLUE (-4925 2550);
FORCEPROP 1 LAST PACK_TYPE C0402
J 0
(-4925 2500);
DISPLAY 0.489362 (-4925 2500);
PAINT SKYBLUE (-4925 2500);
FORCEPROP 1 LAST VOLTAGE 25V
J 0
(-4925 2700);
DISPLAY 0.489362 (-4925 2700);
PAINT SKYBLUE (-4925 2700);
FORCEPROP 2 LAST CDS_LIB pure_quanta
J 0
(-4975 2700);
DISPLAY INVISIBLE (-4975 2700);
FORCEPROP 1 LAST PATH I67
J 0
(-4925 2850);
DISPLAY 0.978723 (-4925 2850);
PAINT WHITE (-4925 2850);
DISPLAY INVISIBLE (-4925 2850);
FORCEADD Q_CAP..1
(-4650 2700);
FORCEPROP 1 LAST LOCATION PC588_2
J 0
(-4600 2800);
DISPLAY 0.489362 (-4600 2800);
PAINT SKYBLUE (-4600 2800);
FORCEPROP 0 LAST $SEC 1
J 0
(-4600 2825);
DISPLAY 0.680851 (-4600 2825);
PAINT MONO (-4600 2825);
DISPLAY INVISIBLE (-4600 2825);
FORCEPROP 0 LAST CDS_SEC 1
J 0
(-4600 2825);
DISPLAY 1.021277 (-4600 2825);
DISPLAY INVISIBLE (-4600 2825);
FORCEPROP 1 LASTPIN (-4650 2800) $PN 1
J 0
(-4640 2780);
DISPLAY 0.489362 (-4640 2780);
PAINT MONO (-4640 2780);
FORCEPROP 1 LASTPIN (-4650 2600) $PN 2
J 0
(-4640 2580);
DISPLAY 0.489362 (-4640 2580);
PAINT MONO (-4640 2580);
FORCEPROP 1 LAST MATERIAL X6S
J 0
(-4600 2600);
DISPLAY 0.489362 (-4600 2600);
PAINT SKYBLUE (-4600 2600);
FORCEPROP 1 LAST TOLERANCE 10%
J 0
(-4600 2650);
DISPLAY 0.489362 (-4600 2650);
PAINT SKYBLUE (-4600 2650);
FORCEPROP 1 LAST VALUE 10UF
J 0
(-4600 2750);
DISPLAY 0.489362 (-4600 2750);
PAINT SKYBLUE (-4600 2750);
FORCEPROP 1 LAST PART_NUMBER CH6104KEA00
J 0
(-4600 2550);
DISPLAY 0.489362 (-4600 2550);
PAINT SKYBLUE (-4600 2550);
FORCEPROP 1 LAST VOLTAGE 25V
J 0
(-4600 2700);
DISPLAY 0.489362 (-4600 2700);
PAINT SKYBLUE (-4600 2700);
FORCEPROP 1 LAST PACK_TYPE C0805
J 0
(-4600 2500);
DISPLAY 0.489362 (-4600 2500);
PAINT SKYBLUE (-4600 2500);
FORCEPROP 2 LAST CDS_LIB pure_quanta
J 0
(-4650 2700);
DISPLAY INVISIBLE (-4650 2700);
FORCEPROP 1 LAST PATH I68
J 0
(-4600 2850);
DISPLAY 0.978723 (-4600 2850);
PAINT WHITE (-4600 2850);
DISPLAY INVISIBLE (-4600 2850);
FORCEADD Q_CAP..1
(-4325 2700);
FORCEPROP 1 LAST LOCATION PC590_2
J 0
(-4275 2800);
DISPLAY 0.489362 (-4275 2800);
PAINT SKYBLUE (-4275 2800);
FORCEPROP 0 LAST $SEC 1
J 0
(-4275 2825);
DISPLAY 0.680851 (-4275 2825);
PAINT MONO (-4275 2825);
DISPLAY INVISIBLE (-4275 2825);
FORCEPROP 0 LAST CDS_SEC 1
J 0
(-4275 2825);
DISPLAY 1.021277 (-4275 2825);
DISPLAY INVISIBLE (-4275 2825);
FORCEPROP 1 LASTPIN (-4325 2800) $PN 1
J 0
(-4315 2780);
DISPLAY 0.489362 (-4315 2780);
PAINT MONO (-4315 2780);
FORCEPROP 1 LASTPIN (-4325 2600) $PN 2
J 0
(-4315 2580);
DISPLAY 0.489362 (-4315 2580);
PAINT MONO (-4315 2580);
FORCEPROP 1 LAST MATERIAL X6S
J 0
(-4275 2600);
DISPLAY 0.489362 (-4275 2600);
PAINT SKYBLUE (-4275 2600);
FORCEPROP 1 LAST TOLERANCE 10%
J 0
(-4275 2650);
DISPLAY 0.489362 (-4275 2650);
PAINT SKYBLUE (-4275 2650);
FORCEPROP 1 LAST VALUE 10UF
J 0
(-4275 2750);
DISPLAY 0.489362 (-4275 2750);
PAINT SKYBLUE (-4275 2750);
FORCEPROP 1 LAST PART_NUMBER CH6104KEA00
J 0
(-4275 2550);
DISPLAY 0.489362 (-4275 2550);
PAINT SKYBLUE (-4275 2550);
FORCEPROP 1 LAST VOLTAGE 25V
J 0
(-4275 2700);
DISPLAY 0.489362 (-4275 2700);
PAINT SKYBLUE (-4275 2700);
FORCEPROP 1 LAST PACK_TYPE C0805
J 0
(-4275 2500);
DISPLAY 0.489362 (-4275 2500);
PAINT SKYBLUE (-4275 2500);
FORCEPROP 2 LAST CDS_LIB pure_quanta
J 0
(-4325 2700);
DISPLAY INVISIBLE (-4325 2700);
FORCEPROP 1 LAST PATH I69
J 0
(-4275 2850);
DISPLAY 0.978723 (-4275 2850);
PAINT WHITE (-4275 2850);
DISPLAY INVISIBLE (-4275 2850);
FORCEADD OFFPAGE..2
R 2
(-7150 4400);
FORCEPROP 2 LAST $XR2 169 
J 0
(-7525 4364);
DISPLAY 0.638298 (-7525 4364);
PAINT MONO (-7525 4364);
FORCEPROP 2 LAST $XR1 175 
J 0
(-7405 4364);
DISPLAY 0.638298 (-7405 4364);
PAINT MONO (-7405 4364);
FORCEPROP 2 LAST $XR0 174 
J 0
(-7405 4400);
DISPLAY 0.638298 (-7405 4400);
PAINT MONO (-7405 4400);
FORCEPROP 2 LAST PATH I7
J 0
(-7100 4475);
DISPLAY 1.021277 (-7100 4475);
DISPLAY INVISIBLE (-7100 4475);
FORCEPROP 1 LAST COMMENT_BODY TRUE
J 2
(-7105 4305);
DISPLAY 0.872340 (-7105 4305);
PAINT GREEN (-7105 4305);
DISPLAY INVISIBLE (-7105 4305);
FORCEPROP 1 LAST OFFPAGE TRUE
J 2
(-7475 4275);
DISPLAY 0.872340 (-7475 4275);
PAINT GREEN (-7475 4275);
DISPLAY INVISIBLE (-7475 4275);
FORCEPROP 2 LAST CDS_LIB standard
J 0
(-7150 4400);
DISPLAY INVISIBLE (-7150 4400);
FORCEADD Q_CAP..1
(-4000 2700);
FORCEPROP 1 LAST LOCATION PC592_2
J 0
(-3950 2800);
DISPLAY 0.489362 (-3950 2800);
PAINT SKYBLUE (-3950 2800);
FORCEPROP 0 LAST $SEC 1
J 0
(-3950 2825);
DISPLAY 0.680851 (-3950 2825);
PAINT MONO (-3950 2825);
DISPLAY INVISIBLE (-3950 2825);
FORCEPROP 0 LAST CDS_SEC 1
J 0
(-3950 2825);
DISPLAY 1.021277 (-3950 2825);
DISPLAY INVISIBLE (-3950 2825);
FORCEPROP 1 LASTPIN (-4000 2800) $PN 1
J 0
(-3990 2780);
DISPLAY 0.489362 (-3990 2780);
PAINT MONO (-3990 2780);
FORCEPROP 1 LASTPIN (-4000 2600) $PN 2
J 0
(-3990 2580);
DISPLAY 0.489362 (-3990 2580);
PAINT MONO (-3990 2580);
FORCEPROP 1 LAST PART_NUMBER CH6104KEA00
J 0
(-3950 2550);
DISPLAY 0.489362 (-3950 2550);
PAINT SKYBLUE (-3950 2550);
FORCEPROP 1 LAST PACK_TYPE C0805
J 0
(-3950 2500);
DISPLAY 0.489362 (-3950 2500);
PAINT SKYBLUE (-3950 2500);
FORCEPROP 1 LAST MATERIAL X6S
J 0
(-3950 2600);
DISPLAY 0.489362 (-3950 2600);
PAINT SKYBLUE (-3950 2600);
FORCEPROP 1 LAST TOLERANCE 10%
J 0
(-3950 2650);
DISPLAY 0.489362 (-3950 2650);
PAINT SKYBLUE (-3950 2650);
FORCEPROP 1 LAST VALUE 10UF
J 0
(-3950 2750);
DISPLAY 0.489362 (-3950 2750);
PAINT SKYBLUE (-3950 2750);
FORCEPROP 1 LAST VOLTAGE 25V
J 0
(-3950 2700);
DISPLAY 0.489362 (-3950 2700);
PAINT SKYBLUE (-3950 2700);
FORCEPROP 2 LAST CDS_LIB pure_quanta
J 0
(-4000 2700);
DISPLAY INVISIBLE (-4000 2700);
FORCEPROP 1 LAST PATH I70
J 0
(-3950 2850);
DISPLAY 0.978723 (-3950 2850);
PAINT WHITE (-3950 2850);
DISPLAY INVISIBLE (-3950 2850);
FORCEADD UNIVERSAL_GND..1
(-3600 2375);
FORCEPROP 3 LASTPIN (-3600 2425) SIG_NAME GND\g
J 0
(-3590 2435);
DISPLAY 0.659574 (-3590 2435);
PAINT MONO (-3590 2435);
DISPLAY INVISIBLE (-3590 2435);
FORCEPROP 2 LAST CDS_LIB pure_quanta_power
J 0
(-3600 2375);
DISPLAY INVISIBLE (-3600 2375);
FORCEPROP 1 LAST PATH I71
J 0
(-3525 2375);
DISPLAY 0.872340 (-3525 2375);
PAINT AQUA (-3525 2375);
DISPLAY INVISIBLE (-3525 2375);
FORCEPROP 1 LAST HDL_POWER GND
J 1
(-3575 2300);
DISPLAY 0.872340 (-3575 2300);
PAINT GREEN (-3575 2300);
DISPLAY INVISIBLE (-3575 2300);
FORCEADD VCC_CORE..1
(-3600 2975);
FORCEPROP 3 LASTPIN (-3600 2925) SIG_NAME SW_P12V_STBY_PVDDCR_SOC_P0_FLT\g
J 0
(-3590 2935);
DISPLAY 0.659574 (-3590 2935);
PAINT MONO (-3590 2935);
DISPLAY INVISIBLE (-3590 2935);
FORCEPROP 1 LAST HDL_POWER SW_P12V_STBY_PVDDCR_SOC_P0_FLT
J 1
(-3600 3025);
DISPLAY 0.489362 (-3600 3025);
PAINT GREEN (-3600 3025);
FORCEPROP 2 LAST CDS_LIB pure_quanta_power
J 0
(-3600 2975);
DISPLAY INVISIBLE (-3600 2975);
FORCEPROP 1 LAST PATH I73
J 0
(-3550 3000);
DISPLAY 0.872340 (-3550 3000);
PAINT AQUA (-3550 3000);
DISPLAY INVISIBLE (-3550 3000);
FORCEADD Q_CAP..1
(-1625 1625);
FORCEPROP 1 LAST LOCATION PC600_2
J 0
(-1575 1725);
DISPLAY 0.489362 (-1575 1725);
PAINT SKYBLUE (-1575 1725);
FORCEPROP 0 LAST $SEC 1
J 0
(-1575 1750);
DISPLAY 0.680851 (-1575 1750);
PAINT MONO (-1575 1750);
DISPLAY INVISIBLE (-1575 1750);
FORCEPROP 0 LAST CDS_SEC 1
J 0
(-1575 1750);
DISPLAY 1.021277 (-1575 1750);
DISPLAY INVISIBLE (-1575 1750);
FORCEPROP 1 LASTPIN (-1625 1725) $PN 1
J 0
(-1615 1705);
DISPLAY 0.489362 (-1615 1705);
PAINT MONO (-1615 1705);
FORCEPROP 1 LASTPIN (-1625 1525) $PN 2
J 0
(-1615 1505);
DISPLAY 0.489362 (-1615 1505);
PAINT MONO (-1615 1505);
FORCEPROP 1 LAST MATERIAL X6S
J 0
(-1575 1525);
DISPLAY 0.489362 (-1575 1525);
PAINT SKYBLUE (-1575 1525);
FORCEPROP 1 LAST TOLERANCE 20%
J 0
(-1575 1575);
DISPLAY 0.489362 (-1575 1575);
PAINT SKYBLUE (-1575 1575);
FORCEPROP 1 LAST VALUE 22UF
J 0
(-1575 1675);
DISPLAY 0.489362 (-1575 1675);
PAINT SKYBLUE (-1575 1675);
FORCEPROP 1 LAST PART_NUMBER TMP_QCH622KMEA01
J 0
(-1575 1475);
DISPLAY 0.489362 (-1575 1475);
PAINT SKYBLUE (-1575 1475);
FORCEPROP 1 LAST VOLTAGE 4V
J 0
(-1575 1625);
DISPLAY 0.489362 (-1575 1625);
PAINT SKYBLUE (-1575 1625);
FORCEPROP 1 LAST PACK_TYPE 0805
J 0
(-1575 1425);
DISPLAY 0.489362 (-1575 1425);
PAINT SKYBLUE (-1575 1425);
FORCEPROP 2 LAST CDS_LIB pure_quanta
J 0
(-1625 1625);
DISPLAY INVISIBLE (-1625 1625);
FORCEPROP 1 LAST PATH I79
J 0
(-1575 1775);
DISPLAY 0.978723 (-1575 1775);
PAINT WHITE (-1575 1775);
DISPLAY INVISIBLE (-1575 1775);
FORCEADD UNIVERSAL_GND..1
(-1200 1275);
FORCEPROP 3 LASTPIN (-1200 1325) SIG_NAME GND\g
J 0
(-1190 1335);
DISPLAY 0.659574 (-1190 1335);
PAINT MONO (-1190 1335);
DISPLAY INVISIBLE (-1190 1335);
FORCEPROP 2 LAST CDS_LIB pure_quanta_power
J 0
(-1200 1275);
DISPLAY INVISIBLE (-1200 1275);
FORCEPROP 1 LAST PATH I80
J 0
(-1125 1275);
DISPLAY 0.872340 (-1125 1275);
PAINT AQUA (-1125 1275);
DISPLAY INVISIBLE (-1125 1275);
FORCEPROP 1 LAST HDL_POWER GND
J 1
(-1175 1200);
DISPLAY 0.872340 (-1175 1200);
PAINT GREEN (-1175 1200);
DISPLAY INVISIBLE (-1175 1200);
FORCEADD Q_CAP..1
(-1200 1625);
FORCEPROP 1 LAST LOCATION PC603_2
J 0
(-1150 1725);
DISPLAY 0.489362 (-1150 1725);
PAINT SKYBLUE (-1150 1725);
FORCEPROP 0 LAST $SEC 1
J 0
(-1150 1750);
DISPLAY 0.680851 (-1150 1750);
PAINT MONO (-1150 1750);
DISPLAY INVISIBLE (-1150 1750);
FORCEPROP 0 LAST CDS_SEC 1
J 0
(-1150 1750);
DISPLAY 1.021277 (-1150 1750);
DISPLAY INVISIBLE (-1150 1750);
FORCEPROP 1 LASTPIN (-1200 1725) $PN 1
J 0
(-1190 1705);
DISPLAY 0.489362 (-1190 1705);
PAINT MONO (-1190 1705);
FORCEPROP 1 LASTPIN (-1200 1525) $PN 2
J 0
(-1190 1505);
DISPLAY 0.489362 (-1190 1505);
PAINT MONO (-1190 1505);
FORCEPROP 1 LAST MATERIAL X6S
J 0
(-1150 1525);
DISPLAY 0.489362 (-1150 1525);
PAINT SKYBLUE (-1150 1525);
FORCEPROP 1 LAST TOLERANCE 20%
J 0
(-1150 1575);
DISPLAY 0.489362 (-1150 1575);
PAINT SKYBLUE (-1150 1575);
FORCEPROP 1 LAST VALUE 22UF
J 0
(-1150 1675);
DISPLAY 0.489362 (-1150 1675);
PAINT SKYBLUE (-1150 1675);
FORCEPROP 1 LAST PART_NUMBER TMP_QCH622KMEA01
J 0
(-1150 1475);
DISPLAY 0.489362 (-1150 1475);
PAINT SKYBLUE (-1150 1475);
FORCEPROP 1 LAST VOLTAGE 4V
J 0
(-1150 1625);
DISPLAY 0.489362 (-1150 1625);
PAINT SKYBLUE (-1150 1625);
FORCEPROP 1 LAST PACK_TYPE 0805
J 0
(-1150 1425);
DISPLAY 0.489362 (-1150 1425);
PAINT SKYBLUE (-1150 1425);
FORCEPROP 2 LAST CDS_LIB pure_quanta
J 0
(-1200 1625);
DISPLAY INVISIBLE (-1200 1625);
FORCEPROP 1 LAST PATH I81
J 0
(-1150 1775);
DISPLAY 0.978723 (-1150 1775);
PAINT WHITE (-1150 1775);
DISPLAY INVISIBLE (-1150 1775);
FORCEADD VCC_CORE..1
(-1200 1950);
FORCEPROP 3 LASTPIN (-1200 1900) SIG_NAME PVDDCR_SOC_P0\g
J 0
(-1190 1910);
DISPLAY 0.659574 (-1190 1910);
PAINT MONO (-1190 1910);
DISPLAY INVISIBLE (-1190 1910);
FORCEPROP 1 LAST HDL_POWER PVDDCR_SOC_P0
J 1
(-1200 2000);
DISPLAY 0.489362 (-1200 2000);
PAINT GREEN (-1200 2000);
FORCEPROP 2 LAST CDS_LIB pure_quanta_power
J 0
(-1200 1950);
DISPLAY INVISIBLE (-1200 1950);
FORCEPROP 1 LAST PATH I82
J 0
(-1150 1975);
DISPLAY 0.872340 (-1150 1975);
PAINT AQUA (-1150 1975);
DISPLAY INVISIBLE (-1150 1975);
FORCEADD Q_INDUCTOR4P_14..1
(-3025 1675);
FORCEPROP 1 LAST LOCATION PL64
J 0
(-3250 1930);
DISPLAY 0.489362 (-3250 1930);
PAINT SKYBLUE (-3250 1930);
FORCEPROP 0 LAST $SEC 1
J 0
(-3250 2075);
DISPLAY 0.680851 (-3250 2075);
PAINT MONO (-3250 2075);
DISPLAY INVISIBLE (-3250 2075);
FORCEPROP 0 LAST CDS_SEC 1
J 0
(-3250 2075);
DISPLAY 1.021277 (-3250 2075);
DISPLAY INVISIBLE (-3250 2075);
FORCEPROP 0 LASTPIN (-3425 1800) $PN 1
J 2
(-3435 1810);
DISPLAY 0.489362 (-3435 1810);
PAINT MONO (-3435 1810);
FORCEPROP 0 LASTPIN (-3425 1550) $PN 2
J 2
(-3435 1560);
DISPLAY 0.489362 (-3435 1560);
PAINT MONO (-3435 1560);
FORCEPROP 0 LASTPIN (-2625 1550) $PN 3
J 0
(-2615 1560);
DISPLAY 0.489362 (-2615 1560);
PAINT MONO (-2615 1560);
FORCEPROP 0 LASTPIN (-2625 1800) $PN 4
J 0
(-2615 1810);
DISPLAY 0.489362 (-2615 1810);
PAINT MONO (-2615 1810);
FORCEPROP 2 LAST PART_TYPE SMLF
J 0
(-3250 2025);
DISPLAY 1.021277 (-3250 2025);
FORCEPROP 1 LAST MATERIAL IND
J 0
(-3250 1885);
DISPLAY 0.489362 (-3250 1885);
PAINT SKYBLUE (-3250 1885);
FORCEPROP 2 LAST VALUE 150NH
J 0
(-3250 1975);
DISPLAY 0.489362 (-3250 1975);
PAINT SKYBLUE (-3250 1975);
FORCEPROP 1 LAST PART_NUMBER CV+15^0TZ04
J 0
(-3250 1835);
DISPLAY 0.489362 (-3250 1835);
PAINT SKYBLUE (-3250 1835);
FORCEPROP 2 LAST CDS_LIB pure_quanta
J 0
(-3025 1675);
DISPLAY INVISIBLE (-3025 1675);
FORCEPROP 1 LAST NEEDS_NO_SIZE TRUE
J 0
(-3025 1675);
DISPLAY 0.468085 (-3025 1675);
PAINT GREEN (-3025 1675);
DISPLAY INVISIBLE (-3025 1675);
FORCEPROP 1 LAST PATH I83
J 0
(-2825 1830);
DISPLAY 0.723404 (-2825 1830);
PAINT GREEN (-2825 1830);
DISPLAY INVISIBLE (-2825 1830);
FORCEADD OFFPAGE..3
R 2
(-4000 1550);
FORCEPROP 2 LAST $XR0 175 
J 0
(-4310 1550);
DISPLAY 0.638298 (-4310 1550);
PAINT MONO (-4310 1550);
FORCEPROP 2 LAST PATH I86
J 2
(-4200 1625);
DISPLAY 1.021277 (-4200 1625);
DISPLAY INVISIBLE (-4200 1625);
FORCEPROP 1 LAST COMMENT_BODY TRUE
J 2
(-3950 1450);
DISPLAY 0.872340 (-3950 1450);
PAINT GREEN (-3950 1450);
DISPLAY INVISIBLE (-3950 1450);
FORCEPROP 1 LAST OFFPAGE TRUE
J 2
(-4325 1425);
DISPLAY 0.872340 (-4325 1425);
PAINT GREEN (-4325 1425);
DISPLAY INVISIBLE (-4325 1425);
FORCEPROP 2 LAST CDS_LIB standard
J 2
(-4000 1550);
DISPLAY INVISIBLE (-4000 1550);
FORCEADD Q_CAPP..1
(-1825 3075);
FORCEPROP 1 LAST LOCATION PC597
J 0
(-1775 3175);
DISPLAY 0.489362 (-1775 3175);
PAINT SKYBLUE (-1775 3175);
FORCEPROP 0 LAST $SEC 1
J 0
(-1775 3200);
DISPLAY 0.680851 (-1775 3200);
PAINT MONO (-1775 3200);
DISPLAY INVISIBLE (-1775 3200);
FORCEPROP 0 LAST CDS_SEC 1
J 0
(-1775 3200);
DISPLAY 1.021277 (-1775 3200);
DISPLAY INVISIBLE (-1775 3200);
FORCEPROP 1 LASTPIN (-1825 3175) $PN 1
J 0
(-1815 3160);
DISPLAY 0.489362 (-1815 3160);
PAINT MONO (-1815 3160);
FORCEPROP 1 LASTPIN (-1825 2975) $PN 2
J 0
(-1815 2960);
DISPLAY 0.489362 (-1815 2960);
PAINT MONO (-1815 2960);
FORCEPROP 1 LAST VALUE 470UF
J 0
(-1775 3125);
DISPLAY 0.489362 (-1775 3125);
PAINT SKYBLUE (-1775 3125);
FORCEPROP 1 LAST MATERIAL EMPTY
J 0
(-1775 2975);
DISPLAY 0.489362 (-1775 2975);
PAINT RED (-1775 2975);
FORCEPROP 1 LAST TOLERANCE 20%
J 0
(-1775 3075);
DISPLAY 0.489362 (-1775 3075);
PAINT SKYBLUE (-1775 3075);
FORCEPROP 1 LAST PART_NUMBER CH747LM8825
J 0
(-1775 2875);
DISPLAY 0.489362 (-1775 2875);
PAINT SKYBLUE (-1775 2875);
FORCEPROP 1 LAST VOLTAGE 2.5V
J 0
(-1775 3025);
DISPLAY 0.489362 (-1775 3025);
PAINT SKYBLUE (-1775 3025);
FORCEPROP 1 LAST PACK_TYPE SMLF
J 0
(-1775 2925);
DISPLAY 0.489362 (-1775 2925);
PAINT SKYBLUE (-1775 2925);
FORCEPROP 2 LAST CDS_LIB pure_quanta
J 0
(-1825 3075);
DISPLAY INVISIBLE (-1825 3075);
FORCEPROP 1 LAST PATH I92
J 0
(-1775 3225);
DISPLAY 0.978723 (-1775 3225);
DISPLAY INVISIBLE (-1775 3225);
FORCEADD Q_CAPP..1
(-1475 3075);
FORCEPROP 1 LAST LOCATION PC598
J 0
(-1425 3175);
DISPLAY 0.489362 (-1425 3175);
PAINT SKYBLUE (-1425 3175);
FORCEPROP 0 LAST $SEC 1
J 0
(-1425 3200);
DISPLAY 0.680851 (-1425 3200);
PAINT MONO (-1425 3200);
DISPLAY INVISIBLE (-1425 3200);
FORCEPROP 0 LAST CDS_SEC 1
J 0
(-1425 3200);
DISPLAY 1.021277 (-1425 3200);
DISPLAY INVISIBLE (-1425 3200);
FORCEPROP 1 LASTPIN (-1475 3175) $PN 1
J 0
(-1465 3160);
DISPLAY 0.489362 (-1465 3160);
PAINT MONO (-1465 3160);
FORCEPROP 1 LASTPIN (-1475 2975) $PN 2
J 0
(-1465 2960);
DISPLAY 0.489362 (-1465 2960);
PAINT MONO (-1465 2960);
FORCEPROP 1 LAST PART_NUMBER CH747LM8825
J 0
(-1425 2875);
DISPLAY 0.489362 (-1425 2875);
PAINT SKYBLUE (-1425 2875);
FORCEPROP 1 LAST PACK_TYPE SMLF
J 0
(-1425 2925);
DISPLAY 0.489362 (-1425 2925);
PAINT SKYBLUE (-1425 2925);
FORCEPROP 1 LAST MATERIAL SPCAP
J 0
(-1425 2975);
DISPLAY 0.489362 (-1425 2975);
PAINT SKYBLUE (-1425 2975);
FORCEPROP 1 LAST TOLERANCE 20%
J 0
(-1425 3075);
DISPLAY 0.489362 (-1425 3075);
PAINT SKYBLUE (-1425 3075);
FORCEPROP 1 LAST VOLTAGE 2.5V
J 0
(-1425 3025);
DISPLAY 0.489362 (-1425 3025);
PAINT SKYBLUE (-1425 3025);
FORCEPROP 1 LAST VALUE 470UF
J 0
(-1425 3125);
DISPLAY 0.489362 (-1425 3125);
PAINT SKYBLUE (-1425 3125);
FORCEPROP 2 LAST CDS_LIB pure_quanta
J 0
(-1475 3075);
DISPLAY INVISIBLE (-1475 3075);
FORCEPROP 1 LAST PATH I94
J 0
(-1425 3225);
DISPLAY 0.978723 (-1425 3225);
DISPLAY INVISIBLE (-1425 3225);
FORCEADD DNS..1
(-4725 1625);
PAINT RED (-4725 1625);
FORCEPROP 2 LAST CDS_LIB mstr_misc
J 0
(-4725 1625);
DISPLAY INVISIBLE (-4725 1625);
FORCEPROP 1 LAST COMMENT_BODY TRUE
R 1
J 0
(-4650 1400);
DISPLAY 0.872340 (-4650 1400);
PAINT GREEN (-4650 1400);
DISPLAY INVISIBLE (-4650 1400);
FORCEADD DNS..1
(-7150 1475);
PAINT RED (-7150 1475);
FORCEPROP 2 LAST CDS_LIB mstr_misc
J 0
(-7150 1475);
DISPLAY INVISIBLE (-7150 1475);
FORCEPROP 1 LAST COMMENT_BODY TRUE
R 1
J 0
(-7075 1250);
DISPLAY 0.872340 (-7075 1250);
PAINT GREEN (-7075 1250);
DISPLAY INVISIBLE (-7075 1250);
FORCEADD DNS..1
(-4675 4225);
PAINT RED (-4675 4225);
FORCEPROP 2 LAST CDS_LIB mstr_misc
J 0
(-4675 4225);
DISPLAY INVISIBLE (-4675 4225);
FORCEPROP 1 LAST COMMENT_BODY TRUE
R 1
J 0
(-4600 4000);
DISPLAY 0.872340 (-4600 4000);
PAINT GREEN (-4600 4000);
DISPLAY INVISIBLE (-4600 4000);
FORCEADD DNS..1
(-4650 4650);
PAINT RED (-4650 4650);
FORCEPROP 2 LAST CDS_LIB mstr_misc
J 0
(-4650 4650);
DISPLAY INVISIBLE (-4650 4650);
FORCEPROP 1 LAST COMMENT_BODY TRUE
R 1
J 0
(-4575 4425);
DISPLAY 0.872340 (-4575 4425);
PAINT GREEN (-4575 4425);
DISPLAY INVISIBLE (-4575 4425);
FORCEADD DNS..1
(-1825 3050);
PAINT RED (-1825 3050);
FORCEPROP 2 LAST CDS_LIB mstr_misc
J 0
(-1825 3050);
DISPLAY INVISIBLE (-1825 3050);
FORCEPROP 1 LAST COMMENT_BODY TRUE
R 1
J 0
(-1750 2825);
DISPLAY 0.872340 (-1750 2825);
PAINT GREEN (-1750 2825);
DISPLAY INVISIBLE (-1750 2825);
FORCEADD DNS..1
(-7200 4575);
PAINT RED (-7200 4575);
FORCEPROP 2 LAST CDS_LIB mstr_misc
J 0
(-7200 4575);
DISPLAY INVISIBLE (-7200 4575);
FORCEPROP 1 LAST COMMENT_BODY TRUE
R 1
J 0
(-7125 4350);
DISPLAY 0.872340 (-7125 4350);
PAINT GREEN (-7125 4350);
DISPLAY INVISIBLE (-7125 4350);
FORCEADD DNS..1
(-4725 1125);
PAINT RED (-4725 1125);
FORCEPROP 2 LAST CDS_LIB mstr_misc
J 0
(-4725 1125);
DISPLAY INVISIBLE (-4725 1125);
FORCEPROP 1 LAST COMMENT_BODY TRUE
R 1
J 0
(-4650 900);
DISPLAY 0.872340 (-4650 900);
PAINT GREEN (-4650 900);
DISPLAY INVISIBLE (-4650 900);
FORCEADD QUANTA_TITLE_BLOCK_C..1
(0 0);
FORCEPROP 0 LAST CDS_CON_LAST_MODIFIED Fri Mar 11 14:53:26 2022
J 0
(-1885 15);
DISPLAY INVISIBLE (-1885 15);
FORCEPROP 1 LAST CUSTOM_TXT_CDS <CON_LAST_MODIFIED>
J 0
(-1885 15);
DISPLAY 0.978723 (-1885 15);
FORCEPROP 2 LAST CUSTOM_TXT_CDS <XR_PAGE_TITLE>
J 0
(-7890 5250);
DISPLAY 0.638298 (-7890 5250);
PAINT PINK (-7890 5250);
DISPLAY INVISIBLE (-7890 5250);
FORCEPROP 1 LAST CUSTOM_TXT_CDS <NAME_2>
J 0
(-3175 50);
FORCEPROP 1 LAST CUSTOM_TXT_CDS <NAME_1>
J 0
(-3175 175);
FORCEPROP 1 LAST CUSTOM_TXT_CDS <Q_NUMBER>
J 0
(-1403 103);
DISPLAY 1.212766 (-1403 103);
FORCEPROP 1 LAST CUSTOM_TXT_CDS <Q_PROJ>
J 0
(-2382 102);
DISPLAY 1.212766 (-2382 102);
FORCEPROP 1 LAST CUSTOM_TXT_CDS <Q_REV>
J 0
(-184 103);
DISPLAY 1.212766 (-184 103);
FORCEPROP 1 LAST CUSTOM_TXT_CDS <CON_PAGE_NUM> OF <CON_TOTAL_PAGES>
J 0
(-446 18);
DISPLAY 0.978723 (-446 18);
FORCEPROP 1 LAST Q_DEPT BU9
J 1
(-3763 49);
DISPLAY 1.957447 (-3763 49);
PAINT GREEN (-3763 49);
FORCEPROP 1 LAST Q_TITLE PVDDCR_SOC_P0 VR PHASE 1&2
J 0
(-9325 50);
DISPLAY 2.446809 (-9325 50);
PAINT GREEN (-9325 50);
FORCEPROP 2 LAST CDS_LIB pure_quanta
J 0
(0 0);
DISPLAY INVISIBLE (0 0);
FORCEPROP 1 LAST CDS_LMAN_SYM_OUTLINE -9475,6775,100,-125
J 0
(0 0);
DISPLAY 0.468085 (0 0);
PAINT GREEN (0 0);
DISPLAY INVISIBLE (0 0);
FORCEPROP 2 LAST PAGE_BORDER TRUE
J 0
(-7890 5250);
DISPLAY 0.638298 (-7890 5250);
PAINT PINK (-7890 5250);
DISPLAY INVISIBLE (-7890 5250);
FORCEPROP 1 LAST COMMENT_BODY TRUE
J 0
(12 -13);
DISPLAY 0.978723 (12 -13);
PAINT GREEN (12 -13);
DISPLAY INVISIBLE (12 -13);
FORCEPROP 2 LAST CDS_XR_PAGE_TITLE CR-174 : @T6G_MB_LIB.T6G(SCH_1):PAGE174
J 0
(-7890 5250);
DISPLAY 0.638298 (-7890 5250);
PAINT PINK (-7890 5250);
DISPLAY INVISIBLE (-7890 5250);
WIRE 16 -1 (-7525 5150)(-7525 5100);
WIRE 16 -1 (-7175 5650)(-7175 5550);
WIRE 16 -1 (-7500 2050)(-7500 2000);
WIRE 16 -1 (-7150 2575)(-7150 2475);
WIRE 16 -1 (-4675 4100)(-4675 4000);
WIRE 16 -1 (-4700 1025)(-4700 950);
WIRE 16 -1 (-7825 1425)(-7825 1300);
WIRE 16 -1 (-7850 4525)(-7850 4400);
WIRE 16 -1 (-7250 1500)(-7500 1500);
WIRE 16 -1 (-7500 1500)(-7500 1375);
WIRE 16 -1 (-7300 4600)(-7525 4600);
WIRE 16 -1 (-7525 4600)(-7525 4475);
WIRE 16 -1 (-1975 4900)(-1975 3725);
WIRE 16 -1 (-1975 4900)(-1700 4900);
WIRE 16 -1 (-2700 4900)(-1975 4900);
WIRE 16 -1 (-1975 3725)(-4100 3725);
WIRE 16 -1 (-1325 4900)(-1700 4900);
WIRE 16 -1 (-1700 4825)(-1700 4900);
WIRE 16 -1 (-875 4900)(-1325 4900);
WIRE 16 -1 (-1325 4900)(-1325 4825);
WIRE 16 -1 (-550 4900)(-875 4900);
WIRE 16 -1 (-875 4900)(-875 4825);
WIRE 16 -1 (-550 4975)(-550 4900);
WIRE 16 -1 (-550 4900)(-550 4800);
WIRE 16 -1 (-3600 2925)(-3600 2875);
WIRE 16 -1 (-3600 2875)(-3600 2800);
WIRE 16 -1 (-3600 2875)(-4000 2875);
WIRE 16 -1 (-4000 2875)(-4000 2800);
WIRE 16 -1 (-4325 2875)(-4000 2875);
WIRE 16 -1 (-4325 2875)(-4325 2800);
WIRE 16 -1 (-4650 2875)(-4325 2875);
WIRE 16 -1 (-4650 2800)(-4650 2875);
WIRE 16 -1 (-4975 2875)(-4650 2875);
WIRE 16 -1 (-4975 2800)(-4975 2875);
WIRE 16 -1 (-5350 2875)(-4975 2875);
WIRE 16 -1 (-5350 2875)(-5350 2800);
WIRE 16 -1 (-5500 2875)(-5350 2875);
WIRE 16 -1 (-5500 2875)(-5500 2450);
WIRE 16 -1 (-5500 2450)(-5500 2400);
WIRE 16 -1 (-5600 2450)(-5500 2450);
WIRE 16 -1 (-5500 2400)(-5600 2400);
WIRE 16 -1 (-6450 1550)(-6900 1550);
FORCEPROP 2 LAST SIG_NAME NC_PVDDCR_SOC_P0_DNC2
J 2
(-6510 1560);
DISPLAY 0.489362 (-6510 1560);
FORCEPROP 2 LASTPROP $XRERR UNIQUE?
J 0
(-7140 1550);
DISPLAY 0.638298 (-7140 1550);
PAINT MONO (-7140 1550);
DISPLAY INVISIBLE (-7140 1550);
WIRE 16 -1 (-3775 1925)(-3775 1900);
WIRE 16 -1 (-3775 1900)(-5600 1900);
FORCEPROP 2 LAST SIG_NAME SW_PVDDCR_SOC_P0_PH2
J 0
(-5485 1910);
DISPLAY 0.489362 (-5485 1910);
FORCEPROP 2 LASTPROP $XRERR UNIQUE?
J 0
(-5725 1910);
DISPLAY 0.638298 (-5725 1910);
PAINT MONO (-5725 1910);
DISPLAY INVISIBLE (-5725 1910);
WIRE 16 -1 (-4700 1800)(-3425 1800);
WIRE 16 -1 (-4700 1800)(-4700 1725);
WIRE 16 -1 (-5600 1800)(-4700 1800);
FORCEPROP 2 LAST SIG_NAME SW_PVDDCR_SOC_P0_SW2
J 0
(-5485 1810);
DISPLAY 0.489362 (-5485 1810);
FORCEPROP 2 LASTPROP $XRERR UNIQUE?
J 0
(-5725 1810);
DISPLAY 0.638298 (-5725 1810);
PAINT MONO (-5725 1810);
DISPLAY INVISIBLE (-5725 1810);
WIRE 16 -1 (-3425 5650)(-3425 5525);
WIRE 16 -1 (-3425 5525)(-3800 5525);
WIRE 16 -1 (-3800 5525)(-3800 5650);
WIRE 16 -1 (-3875 5525)(-3800 5525);
WIRE 16 -1 (-3875 5475)(-3875 5525);
WIRE 16 -1 (-4150 5525)(-3875 5525);
WIRE 16 -1 (-4150 5650)(-4150 5525);
WIRE 16 -1 (-4150 5525)(-4450 5525);
WIRE 16 -1 (-4450 5650)(-4450 5525);
WIRE 16 -1 (-4775 5525)(-4450 5525);
WIRE 16 -1 (-4775 5650)(-4775 5525);
WIRE 16 -1 (-5100 5525)(-4775 5525);
WIRE 16 -1 (-5100 5650)(-5100 5525);
WIRE 16 -1 (-5425 5525)(-5100 5525);
WIRE 16 -1 (-5425 5650)(-5425 5525);
WIRE 16 -1 (-5625 5250)(-4825 5250);
FORCEPROP 2 LAST SIG_NAME SW_PVDDCR_SOC_P0_BOOT1
J 0
(-5535 5260);
DISPLAY 0.489362 (-5535 5260);
FORCEPROP 2 LASTPROP $XRERR UNIQUE?
J 0
(-5775 5260);
DISPLAY 0.638298 (-5775 5260);
PAINT MONO (-5775 5260);
DISPLAY INVISIBLE (-5775 5260);
WIRE 16 -1 (-5625 4900)(-4675 4900);
FORCEPROP 2 LAST SIG_NAME SW_PVDDCR_SOC_P0_SW1
J 0
(-5535 4910);
DISPLAY 0.489362 (-5535 4910);
FORCEPROP 2 LASTPROP $XRERR UNIQUE?
J 0
(-5775 4910);
DISPLAY 0.638298 (-5775 4910);
PAINT MONO (-5775 4910);
DISPLAY INVISIBLE (-5775 4910);
WIRE 16 -1 (-3500 4900)(-4675 4900);
WIRE 16 -1 (-4675 4900)(-4675 4750);
WIRE 16 -1 (-3875 5025)(-3875 5000);
WIRE 16 -1 (-3875 5000)(-5625 5000);
FORCEPROP 2 LAST SIG_NAME SW_PVDDCR_SOC_P0_PH1
J 0
(-5535 5010);
DISPLAY 0.489362 (-5535 5010);
FORCEPROP 2 LASTPROP $XRERR UNIQUE?
J 0
(-5775 5010);
DISPLAY 0.638298 (-5775 5010);
PAINT MONO (-5775 5010);
DISPLAY INVISIBLE (-5775 5010);
WIRE 16 -1 (-1700 4500)(-1325 4500);
WIRE 16 -1 (-1700 4500)(-1700 4625);
WIRE 16 -1 (-875 4500)(-1325 4500);
WIRE 16 -1 (-1325 4625)(-1325 4500);
WIRE 16 -1 (-875 4625)(-875 4500);
WIRE 16 -1 (-550 4500)(-875 4500);
WIRE 16 -1 (-550 4600)(-550 4500);
WIRE 16 -1 (-550 4350)(-550 4500);
WIRE 16 -1 (-2675 5975)(-2675 5925);
WIRE 16 -1 (-2675 5925)(-2875 5925);
WIRE 16 -1 (-2225 4550)(-2225 4650);
WIRE 16 -1 (-2225 4650)(-2700 4650);
WIRE 16 -1 (-4625 5250)(-3875 5250);
FORCEPROP 2 LAST SIG_NAME SW_PVDDCR_SOC_P0_BOOT1_RC
J 2
(-3910 5260);
DISPLAY 0.489362 (-3910 5260);
FORCEPROP 2 LASTPROP $XRERR UNIQUE?
J 0
(-4150 5260);
DISPLAY 0.638298 (-4150 5260);
PAINT MONO (-4150 5260);
DISPLAY INVISIBLE (-4150 5260);
WIRE 16 -1 (-3875 5250)(-3875 5225);
WIRE 16 -1 (-3950 4650)(-3500 4650);
FORCEPROP 2 LAST SIG_NAME IND_SOC_P0_CPL2
J 0
(-3935 4660);
DISPLAY 0.489362 (-3935 4660);
WIRE 16 -1 (-1150 3275)(-1150 3300);
WIRE 16 -1 (-1150 3175)(-1150 3275);
WIRE 16 -1 (-1150 3275)(-1475 3275);
WIRE 16 -1 (-1475 3175)(-1475 3275);
WIRE 16 -1 (-1825 3275)(-1475 3275);
WIRE 16 -1 (-1825 3175)(-1825 3275);
WIRE 16 -1 (-1625 1525)(-1625 1400);
WIRE 16 -1 (-1200 1400)(-1625 1400);
WIRE 16 -1 (-1200 1325)(-1200 1400);
WIRE 16 -1 (-1200 1525)(-1200 1400);
WIRE 16 -1 (-2250 1550)(-2625 1550);
FORCEPROP 2 LAST SIG_NAME IND_SOC_P0_CPL2
J 0
(-2585 1560);
DISPLAY 0.489362 (-2585 1560);
WIRE 16 -1 (-3950 1550)(-3425 1550);
FORCEPROP 2 LAST SIG_NAME IND_SOC_P0_CPL3
J 0
(-3885 1560);
DISPLAY 0.489362 (-3885 1560);
WIRE 16 -1 (-6475 4400)(-7100 4400);
FORCEPROP 2 LAST SIG_NAME PVDDCR_SOC_P0_TEMP1
J 2
(-6535 4410);
DISPLAY 0.489362 (-6535 4410);
WIRE 16 -1 (-6475 4900)(-7125 4900);
FORCEPROP 2 LAST SIG_NAME PVDDCR_SOC_P0_IMON1
J 2
(-6535 4910);
DISPLAY 0.489362 (-6535 4910);
WIRE 16 -1 (-6475 4300)(-7075 4300);
FORCEPROP 2 LAST SIG_NAME PVDDCR_SOC_P0_PWM1
J 2
(-6535 4310);
DISPLAY 0.489362 (-6535 4310);
WIRE 16 -1 (-6475 4650)(-6925 4650);
FORCEPROP 2 LAST SIG_NAME NC_PVDDCR_SOC_P0_DNC1
J 2
(-6535 4660);
DISPLAY 0.489362 (-6535 4660);
FORCEPROP 2 LASTPROP $XRERR UNIQUE?
J 0
(-7165 4650);
DISPLAY 0.638298 (-7165 4650);
PAINT MONO (-7165 4650);
DISPLAY INVISIBLE (-7165 4650);
WIRE 16 -1 (-7100 4600)(-6475 4600);
FORCEPROP 2 LAST SIG_NAME PVDDCR_SOC_P0_LSET1
J 2
(-6535 4610);
DISPLAY 0.489362 (-6535 4610);
FORCEPROP 2 LASTPROP $XRERR UNIQUE?
J 0
(-6775 4610);
DISPLAY 0.638298 (-6775 4610);
PAINT MONO (-6775 4610);
DISPLAY INVISIBLE (-6775 4610);
WIRE 16 -1 (-8025 4800)(-7850 4800);
WIRE 16 -1 (-6475 4800)(-7850 4800);
FORCEPROP 2 LAST SIG_NAME PVDDCR_CPU0_P0_VCCS
J 2
(-6535 4810);
DISPLAY 0.489362 (-6535 4810);
WIRE 16 -1 (-7850 4725)(-7850 4800);
WIRE 16 -1 (-7525 5850)(-7525 5975);
WIRE 16 -1 (-7175 5975)(-7525 5975);
WIRE 16 -1 (-7525 6100)(-7525 5975);
WIRE 16 -1 (-6825 5975)(-7175 5975);
WIRE 16 -1 (-7175 5850)(-7175 5975);
WIRE 16 -1 (-6825 5550)(-6825 5975);
WIRE 16 -1 (-6825 5550)(-6475 5550);
WIRE 16 -1 (-5600 2150)(-4775 2150);
FORCEPROP 2 LAST SIG_NAME SW_PVDDCR_SOC_P0_BOOT2
J 0
(-5485 2160);
DISPLAY 0.489362 (-5485 2160);
FORCEPROP 2 LASTPROP $XRERR UNIQUE?
J 0
(-5725 2160);
DISPLAY 0.638298 (-5725 2160);
PAINT MONO (-5725 2160);
DISPLAY INVISIBLE (-5725 2160);
WIRE 16 -1 (-4700 1525)(-4700 1225);
FORCEPROP 2 LAST SIG_NAME SW_PVDDCR_SOC_P0_SW2_RC
J 0
(-4660 1335);
DISPLAY 0.489362 (-4660 1335);
FORCEPROP 2 LASTPROP $XRERR UNIQUE?
J 0
(-4900 1335);
DISPLAY 0.638298 (-4900 1335);
PAINT MONO (-4900 1335);
DISPLAY INVISIBLE (-4900 1335);
WIRE 16 -1 (-5600 1500)(-5075 1500);
FORCEPROP 2 LAST SIG_NAME NC_PVDDCR_SOC_P0_GL1_2
J 0
(-5485 1510);
DISPLAY 0.489362 (-5485 1510);
FORCEPROP 2 LASTPROP $XRERR UNIQUE?
J 0
(-5045 1500);
DISPLAY 0.638298 (-5045 1500);
PAINT MONO (-5045 1500);
DISPLAY INVISIBLE (-5045 1500);
WIRE 16 -1 (-5600 1450)(-5075 1450);
FORCEPROP 2 LAST SIG_NAME NC_PVDDCR_SOC_P0_GL2_2
J 0
(-5485 1460);
DISPLAY 0.489362 (-5485 1460);
FORCEPROP 2 LASTPROP $XRERR UNIQUE?
J 0
(-5045 1450);
DISPLAY 0.638298 (-5045 1450);
PAINT MONO (-5045 1450);
DISPLAY INVISIBLE (-5045 1450);
WIRE 16 -1 (-5600 1200)(-5425 1200);
WIRE 16 -1 (-5425 1200)(-5425 1250);
WIRE 16 -1 (-5425 1150)(-5425 1200);
WIRE 16 -1 (-5600 1250)(-5425 1250);
WIRE 16 -1 (-5425 1250)(-5425 1300);
WIRE 16 -1 (-5425 1350)(-5425 1300);
WIRE 16 -1 (-5600 1300)(-5425 1300);
WIRE 16 -1 (-5425 1350)(-5600 1350);
WIRE 16 -1 (-7000 2150)(-7000 1950);
WIRE 16 -1 (-7000 2150)(-6450 2150);
WIRE 16 -1 (-7000 2325)(-7000 2150);
FORCEPROP 2 LAST SIG_NAME PVDDCR_SOC_P0_VCC2
J 2
(-6535 2160);
DISPLAY 0.489362 (-6535 2160);
FORCEPROP 2 LASTPROP $XRERR UNIQUE?
J 0
(-6775 2160);
DISPLAY 0.638298 (-6775 2160);
PAINT MONO (-6775 2160);
DISPLAY INVISIBLE (-6775 2160);
WIRE 16 -1 (-7000 1950)(-6450 1950);
WIRE 16 -1 (-7500 2325)(-7000 2325);
WIRE 16 -1 (-7500 2575)(-7500 2325);
WIRE 16 -1 (-7500 2325)(-7500 2250);
WIRE 16 -1 (-6450 1800)(-7100 1800);
FORCEPROP 2 LAST SIG_NAME PVDDCR_SOC_P0_IMON2
J 2
(-6510 1810);
DISPLAY 0.489362 (-6510 1810);
WIRE 16 -1 (-6450 1300)(-7075 1300);
FORCEPROP 2 LAST SIG_NAME PVDDCR_SOC_P0_TEMP1
J 2
(-6510 1310);
DISPLAY 0.489362 (-6510 1310);
WIRE 16 -1 (-6450 1200)(-7050 1200);
FORCEPROP 2 LAST SIG_NAME PVDDCR_SOC_P0_PWM2
J 2
(-6510 1210);
DISPLAY 0.489362 (-6510 1210);
WIRE 16 -1 (-7050 1500)(-6450 1500);
FORCEPROP 2 LAST SIG_NAME PVDDCR_SOC_P0_LSET2
J 2
(-6510 1510);
DISPLAY 0.489362 (-6510 1510);
FORCEPROP 2 LASTPROP $XRERR UNIQUE?
J 0
(-6750 1510);
DISPLAY 0.638298 (-6750 1510);
PAINT MONO (-6750 1510);
DISPLAY INVISIBLE (-6750 1510);
WIRE 16 -1 (-8000 1700)(-7825 1700);
WIRE 16 -1 (-6450 1700)(-7825 1700);
FORCEPROP 2 LAST SIG_NAME PVDDCR_CPU0_P0_VCCS
J 2
(-6510 1710);
DISPLAY 0.489362 (-6510 1710);
WIRE 16 -1 (-7825 1625)(-7825 1700);
WIRE 16 -1 (-7500 2775)(-7500 2900);
WIRE 16 -1 (-7150 2900)(-7500 2900);
WIRE 16 -1 (-7500 3025)(-7500 2900);
WIRE 16 -1 (-6800 2900)(-7150 2900);
WIRE 16 -1 (-7150 2775)(-7150 2900);
WIRE 16 -1 (-6800 2450)(-6800 2900);
WIRE 16 -1 (-6800 2450)(-6450 2450);
WIRE 16 -1 (-5625 4300)(-5450 4300);
WIRE 16 -1 (-5450 4225)(-5450 4300);
WIRE 16 -1 (-5450 4300)(-5450 4350);
WIRE 16 -1 (-5625 4350)(-5450 4350);
WIRE 16 -1 (-5450 4350)(-5450 4400);
WIRE 16 -1 (-5450 4450)(-5450 4400);
WIRE 16 -1 (-5625 4400)(-5450 4400);
WIRE 16 -1 (-5450 4450)(-5625 4450);
WIRE 16 -1 (-5625 4550)(-5100 4550);
FORCEPROP 2 LAST SIG_NAME NC_PVDDCR_SOC_P0_GL2_1
J 0
(-5535 4560);
DISPLAY 0.489362 (-5535 4560);
FORCEPROP 2 LASTPROP $XRERR UNIQUE?
J 0
(-5070 4550);
DISPLAY 0.638298 (-5070 4550);
PAINT MONO (-5070 4550);
DISPLAY INVISIBLE (-5070 4550);
WIRE 16 -1 (-3425 5850)(-3425 5925);
WIRE 16 -1 (-3075 5925)(-3425 5925);
WIRE 16 -1 (-3425 5925)(-3800 5925);
WIRE 16 -1 (-3800 5850)(-3800 5925);
WIRE 16 -1 (-3875 5925)(-3800 5925);
WIRE 16 -1 (-3875 5975)(-3875 5925);
WIRE 16 -1 (-4150 5925)(-3875 5925);
WIRE 16 -1 (-4150 5925)(-4150 5850);
WIRE 16 -1 (-4450 5925)(-4150 5925);
WIRE 16 -1 (-4450 5925)(-4450 5850);
WIRE 16 -1 (-4775 5925)(-4450 5925);
WIRE 16 -1 (-4775 5850)(-4775 5925);
WIRE 16 -1 (-5100 5925)(-4775 5925);
WIRE 16 -1 (-5100 5850)(-5100 5925);
WIRE 16 -1 (-5425 5925)(-5100 5925);
WIRE 16 -1 (-5425 5850)(-5425 5925);
WIRE 16 -1 (-5525 5925)(-5425 5925);
WIRE 16 -1 (-5525 5925)(-5525 5550);
WIRE 16 -1 (-5625 5550)(-5525 5550);
WIRE 16 -1 (-5525 5550)(-5525 5500);
WIRE 16 -1 (-5525 5500)(-5625 5500);
WIRE 16 -1 (-4575 2150)(-3775 2150);
FORCEPROP 2 LAST SIG_NAME SW_PVDDCR_SOC_P0_BOOT2_RC
J 2
(-3810 2160);
DISPLAY 0.489362 (-3810 2160);
FORCEPROP 2 LASTPROP $XRERR UNIQUE?
J 0
(-4050 2160);
DISPLAY 0.638298 (-4050 2160);
PAINT MONO (-4050 2160);
DISPLAY INVISIBLE (-4050 2160);
WIRE 16 -1 (-3775 2150)(-3775 2125);
WIRE 16 -1 (-4675 4550)(-4675 4300);
FORCEPROP 2 LAST SIG_NAME SW_PVDDCR_SOC_P0_SW1_RC
J 0
(-4635 4385);
DISPLAY 0.489362 (-4635 4385);
FORCEPROP 2 LASTPROP $XRERR UNIQUE?
J 0
(-4875 4385);
DISPLAY 0.638298 (-4875 4385);
PAINT MONO (-4875 4385);
DISPLAY INVISIBLE (-4875 4385);
WIRE 16 -1 (-5625 4600)(-5100 4600);
FORCEPROP 2 LAST SIG_NAME NC_PVDDCR_SOC_P0_GL1_1
J 0
(-5535 4610);
DISPLAY 0.489362 (-5535 4610);
FORCEPROP 2 LASTPROP $XRERR UNIQUE?
J 0
(-5070 4600);
DISPLAY 0.638298 (-5070 4600);
PAINT MONO (-5070 4600);
DISPLAY INVISIBLE (-5070 4600);
WIRE 16 -1 (-7025 5250)(-7025 5050);
WIRE 16 -1 (-7025 5250)(-6475 5250);
WIRE 16 -1 (-7025 5425)(-7025 5250);
FORCEPROP 2 LAST SIG_NAME PVDDCR_SOC_P0_VCC1
J 2
(-6535 5260);
DISPLAY 0.489362 (-6535 5260);
FORCEPROP 2 LASTPROP $XRERR UNIQUE?
J 0
(-6775 5260);
DISPLAY 0.638298 (-6775 5260);
PAINT MONO (-6775 5260);
DISPLAY INVISIBLE (-6775 5260);
WIRE 16 -1 (-7025 5050)(-6475 5050);
WIRE 16 -1 (-7525 5425)(-7025 5425);
WIRE 16 -1 (-7525 5650)(-7525 5425);
WIRE 16 -1 (-7525 5425)(-7525 5350);
WIRE 16 -1 (-5625 4650)(-4900 4650);
WIRE 16 -1 (-4900 3725)(-4900 4650);
WIRE 16 -1 (-4300 3725)(-4900 3725);
FORCEPROP 2 LAST SIG_NAME PVDDCR_SOC_P0_VOS1
J 0
(-5535 4675);
DISPLAY 0.489362 (-5535 4675);
FORCEPROP 2 LASTPROP $XRERR UNIQUE?
J 0
(-5775 4675);
DISPLAY 0.638298 (-5775 4675);
PAINT MONO (-5775 4675);
DISPLAY INVISIBLE (-5775 4675);
WIRE 16 -1 (-3600 2600)(-3600 2475);
WIRE 16 -1 (-3600 2475)(-3600 2425);
WIRE 16 -1 (-3600 2475)(-4000 2475);
WIRE 16 -1 (-4000 2600)(-4000 2475);
WIRE 16 -1 (-4325 2475)(-4000 2475);
WIRE 16 -1 (-4325 2600)(-4325 2475);
WIRE 16 -1 (-4650 2475)(-4325 2475);
WIRE 16 -1 (-4650 2600)(-4650 2475);
WIRE 16 -1 (-4975 2475)(-4650 2475);
WIRE 16 -1 (-4975 2600)(-4975 2475);
WIRE 16 -1 (-5350 2475)(-4975 2475);
WIRE 16 -1 (-5350 2600)(-5350 2475);
WIRE 16 -1 (-4325 800)(-4900 800);
FORCEPROP 2 LAST SIG_NAME PVDDCR_SOC_P0_VOS2
J 0
(-5485 1575);
DISPLAY 0.489362 (-5485 1575);
FORCEPROP 2 LASTPROP $XRERR UNIQUE?
J 0
(-5725 1575);
DISPLAY 0.638298 (-5725 1575);
PAINT MONO (-5725 1575);
DISPLAY INVISIBLE (-5725 1575);
WIRE 16 -1 (-4900 800)(-4900 1550);
WIRE 16 -1 (-5600 1550)(-4900 1550);
WIRE 16 -1 (-1975 1800)(-1975 800);
WIRE 16 -1 (-2625 1800)(-1975 1800);
WIRE 16 -1 (-1975 1800)(-1625 1800);
WIRE 16 -1 (-1975 800)(-4125 800);
WIRE 16 -1 (-1625 1800)(-1200 1800);
WIRE 16 -1 (-1625 1800)(-1625 1725);
WIRE 16 -1 (-1200 1900)(-1200 1800);
WIRE 16 -1 (-1200 1800)(-1200 1725);
WIRE 17 273 (-600 2525)(-600 3550);
WIRE 17 273 (-2200 2525)(-600 2525);
WIRE 17 273 (-600 3550)(-2200 3550);
WIRE 17 273 (-2200 3550)(-2200 2525);
WIRE 16 -1 (-1150 2775)(-1150 2825);
WIRE 16 -1 (-1150 2975)(-1150 2825);
WIRE 16 -1 (-1150 2825)(-1475 2825);
WIRE 16 -1 (-1475 2975)(-1475 2825);
WIRE 16 -1 (-1475 2825)(-1825 2825);
WIRE 16 -1 (-1825 2975)(-1825 2825);
DOT 1 (-4650 2875);
DOT 1 (-3425 5925);
DOT 1 (-4975 2475);
DOT 1 (-1700 4900);
DOT 1 (-550 4900);
DOT 1 (-875 4900);
DOT 1 (-550 4500);
DOT 1 (-875 4500);
DOT 1 (-1325 4900);
DOT 1 (-1325 4500);
DOT 1 (-3800 5925);
DOT 1 (-3875 5925);
DOT 1 (-3875 5525);
DOT 1 (-4150 5925);
DOT 1 (-4450 5925);
DOT 1 (-4450 5525);
DOT 1 (-4775 5925);
DOT 1 (-5100 5925);
DOT 1 (-4775 5525);
DOT 1 (-5100 5525);
DOT 1 (-4675 4900);
DOT 1 (-5425 5925);
DOT 1 (-5525 5550);
DOT 1 (-5450 4400);
DOT 1 (-5450 4350);
DOT 1 (-5450 4300);
DOT 1 (-7025 5250);
DOT 1 (-7175 5975);
DOT 1 (-7525 5975);
DOT 1 (-7525 5425);
DOT 1 (-7850 4800);
DOT 1 (-7825 1700);
DOT 1 (-7000 2150);
DOT 1 (-7500 2325);
DOT 1 (-7500 2900);
DOT 1 (-7150 2900);
DOT 1 (-5425 1200);
DOT 1 (-5425 1250);
DOT 1 (-5425 1300);
DOT 1 (-4700 1800);
DOT 1 (-5500 2450);
DOT 1 (-5350 2875);
DOT 1 (-4650 2475);
DOT 1 (-4975 2875);
DOT 1 (-4325 2475);
DOT 1 (-4325 2875);
DOT 1 (-4000 2475);
DOT 1 (-3600 2475);
DOT 1 (-4000 2875);
DOT 1 (-3600 2875);
DOT 1 (-1975 1800);
DOT 1 (-1625 1800);
DOT 1 (-1200 1400);
DOT 1 (-1200 1800);
DOT 1 (-1475 2825);
DOT 1 (-1150 2825);
DOT 1 (-1475 3275);
DOT 1 (-3800 5525);
DOT 1 (-4150 5525);
DOT 1 (-1150 3275);
DOT 1 (-1975 4900);
FORCENOTE
PR358,PR359,PR365 = CS00002JB38
(-9175 575) 0;
DISPLAY LEFT (-9175 575);
DISPLAY 0.808511 (-9175 575);
PAINT WHITE (-9175 575);
FORCENOTE
PC577_7,PC578_8,PC605_9 = EMPTY
(-9175 650) 0;
DISPLAY LEFT (-9175 650);
DISPLAY 0.808511 (-9175 650);
PAINT WHITE (-9175 650);
FORCENOTE
PR362,PR363,PR367 = EMPTY
(-9175 725) 0;
DISPLAY LEFT (-9175 725);
DISPLAY 0.808511 (-9175 725);
PAINT WHITE (-9175 725);
FORCENOTE
PR360,PR361,PR366 = CS00002JB38
(-9175 800) 0;
DISPLAY LEFT (-9175 800);
DISPLAY 0.808511 (-9175 800);
PAINT WHITE (-9175 800);
FORCENOTE
3RD SOURCE:MPS BOM
(-9175 525) 0;
DISPLAY LEFT (-9175 525);
DISPLAY 0.808511 (-9175 525);
PAINT WHITE (-9175 525);
FORCENOTE
PU49,PU50,PU51=AL087000A02
(-9175 450) 0;
DISPLAY LEFT (-9175 450);
DISPLAY 0.808511 (-9175 450);
PAINT WHITE (-9175 450);
FORCENOTE
PR360,PR361,PR366=CS00002JB38
(-9175 375) 0;
DISPLAY LEFT (-9175 375);
DISPLAY 0.808511 (-9175 375);
PAINT WHITE (-9175 375);
FORCENOTE
PC577_7,PC578_8,PC605_9=EMPTY
(-9175 300) 0;
DISPLAY LEFT (-9175 300);
DISPLAY 0.808511 (-9175 300);
PAINT WHITE (-9175 300);
FORCENOTE
PR362,PR363,PR367=EMPTY
(-9175 225) 0;
DISPLAY LEFT (-9175 225);
DISPLAY 0.808511 (-9175 225);
PAINT WHITE (-9175 225);
FORCENOTE
MAIN SOURCE:RENESAS BOM
(-9175 1150) 0;
DISPLAY LEFT (-9175 1150);
DISPLAY 0.808511 (-9175 1150);
PAINT WHITE (-9175 1150);
FORCENOTE
PU49,PU50,PU51 = AL021590000/TDA21590
(-9175 875) 0;
DISPLAY LEFT (-9175 875);
DISPLAY 0.808511 (-9175 875);
PAINT WHITE (-9175 875);
FORCENOTE
PU49,PU50,PU51=AL099390004/ISL99390FRZ-TR5935
(-9175 1075) 0;
DISPLAY LEFT (-9175 1075);
DISPLAY 0.808511 (-9175 1075);
PAINT WHITE (-9175 1075);
FORCENOTE
2ND=CH747LM8822
(-1650 2650) 0;
DISPLAY LEFT (-1650 2650);
DISPLAY 0.638298 (-1650 2650);
PAINT WHITE (-1650 2650);
FORCENOTE
7.3*4.3*1.9
(-1650 2700) 0;
DISPLAY LEFT (-1650 2700);
DISPLAY 0.638298 (-1650 2700);
PAINT WHITE (-1650 2700);
FORCENOTE
ESR=4.5M OHM
(-1650 2750) 0;
DISPLAY LEFT (-1650 2750);
DISPLAY 0.638298 (-1650 2750);
PAINT WHITE (-1650 2750);
FORCENOTE
DCR=2-3,0.27M OHM
(-2600 1900) 0;
DISPLAY LEFT (-2600 1900);
DISPLAY 0.638298 (-2600 1900);
PAINT WHITE (-2600 1900);
FORCENOTE
2ND SOURCE:INFENEON BOM
(-9175 950) 0;
DISPLAY LEFT (-9175 950);
DISPLAY 0.808511 (-9175 950);
PAINT WHITE (-9175 950);
FORCENOTE
PG2292.500HLT
(-3125 5850) 0;
DISPLAY LEFT (-3125 5850);
DISPLAY 0.638298 (-3125 5850);
PAINT WHITE (-3125 5850);
FORCENOTE
ISAT:70A@100C
(-3125 5800) 0;
DISPLAY LEFT (-3125 5800);
DISPLAY 0.638298 (-3125 5800);
PAINT WHITE (-3125 5800);
FORCENOTE
6.0*6.1*7.0
(-3125 5750) 0;
DISPLAY LEFT (-3125 5750);
DISPLAY 0.638298 (-3125 5750);
PAINT WHITE (-3125 5750);
FORCENOTE
DCR=0.09M OHM
(-3125 5700) 0;
DISPLAY LEFT (-3125 5700);
DISPLAY 0.638298 (-3125 5700);
PAINT WHITE (-3125 5700);
FORCENOTE
2ND=CVA50^0MZ07
(-3125 5650) 0;
DISPLAY LEFT (-3125 5650);
DISPLAY 0.638298 (-3125 5650);
PAINT WHITE (-3125 5650);
FORCENOTE
3RD=CVA50^0MZ08
(-3125 5600) 0;
DISPLAY LEFT (-3125 5600);
DISPLAY 0.638298 (-3125 5600);
PAINT WHITE (-3125 5600);
FORCENOTE
3RD=CC72204MD03
(-3550 5275) 0;
DISPLAY LEFT (-3550 5275);
DISPLAY 0.638298 (-3550 5275);
PAINT WHITE (-3550 5275);
FORCENOTE
2ND=CC72204MD01
(-3550 5325) 0;
DISPLAY LEFT (-3550 5325);
DISPLAY 0.638298 (-3550 5325);
PAINT WHITE (-3550 5325);
FORCENOTE
ESR=16M OHM
(-3550 5475) 0;
DISPLAY LEFT (-3550 5475);
DISPLAY 0.638298 (-3550 5475);
PAINT WHITE (-3550 5475);
FORCENOTE
IRIPPLE:4.65A
(-3550 5425) 0;
DISPLAY LEFT (-3550 5425);
DISPLAY 0.638298 (-3550 5425);
PAINT WHITE (-3550 5425);
FORCENOTE
8*11.5
(-3550 5375) 0;
DISPLAY LEFT (-3550 5375);
DISPLAY 0.638298 (-3550 5375);
PAINT WHITE (-3550 5375);
FORCENOTE
PGL6303.151HLT
(-2675 5200) 0;
DISPLAY LEFT (-2675 5200);
DISPLAY 0.638298 (-2675 5200);
PAINT WHITE (-2675 5200);
FORCENOTE
ISAT:70A@100C
(-2675 5150) 0;
DISPLAY LEFT (-2675 5150);
DISPLAY 0.638298 (-2675 5150);
PAINT WHITE (-2675 5150);
FORCENOTE
11.0*7.5*12.5
(-2675 5100) 0;
DISPLAY LEFT (-2675 5100);
DISPLAY 0.638298 (-2675 5100);
PAINT WHITE (-2675 5100);
FORCENOTE
DCR=1-4,0.105M OHM
(-2675 5050) 0;
DISPLAY LEFT (-2675 5050);
DISPLAY 0.638298 (-2675 5050);
PAINT WHITE (-2675 5050);
FORCENOTE
DCR=2-3,0.27M OHM
(-2675 5000) 0;
DISPLAY LEFT (-2675 5000);
DISPLAY 0.638298 (-2675 5000);
PAINT WHITE (-2675 5000);
FORCENOTE
2ND=CV+15^0TZ01
(-2675 4950) 0;
DISPLAY LEFT (-2675 4950);
DISPLAY 0.638298 (-2675 4950);
PAINT WHITE (-2675 4950);
FORCENOTE
PVDDCR_SOC_P0_PHASE2
(-6575 3200) 0;
DISPLAY LEFT (-6575 3200);
DISPLAY 1.595745 (-6575 3200);
PAINT WHITE (-6575 3200);
FORCENOTE
BOM NOTE
(-9175 1225) 0;
DISPLAY LEFT (-9175 1225);
DISPLAY 1.276596 (-9175 1225);
PAINT WHITE (-9175 1225);
FORCENOTE
2ND=CV+15^0TZ01
(-2600 1850) 0;
DISPLAY LEFT (-2600 1850);
DISPLAY 0.638298 (-2600 1850);
PAINT WHITE (-2600 1850);
FORCENOTE
PVDDCR_SOC_P0_PHASE1
(-6600 6300) 0;
DISPLAY LEFT (-6600 6300);
DISPLAY 1.595745 (-6600 6300);
PAINT WHITE (-6600 6300);
FORCENOTE
DCR=1-4,0.105M OHM
(-2600 1950) 0;
DISPLAY LEFT (-2600 1950);
DISPLAY 0.638298 (-2600 1950);
PAINT WHITE (-2600 1950);
FORCENOTE
11.0*7.5*12.5
(-2600 2000) 0;
DISPLAY LEFT (-2600 2000);
DISPLAY 0.638298 (-2600 2000);
PAINT WHITE (-2600 2000);
FORCENOTE
ISAT:70A@100C
(-2600 2050) 0;
DISPLAY LEFT (-2600 2050);
DISPLAY 0.638298 (-2600 2050);
PAINT WHITE (-2600 2050);
FORCENOTE
PGL6303.151HLT
(-2600 2100) 0;
DISPLAY LEFT (-2600 2100);
DISPLAY 0.638298 (-2600 2100);
PAINT WHITE (-2600 2100);
QUIT
